FILE_TYPE = MACRO_DRAWING;
SET COLOR_WIRE YELLOW;
SET COLOR_PROP ORANGE;
SET COLOR_DOT WHITE;
SET COLOR_ARC YELLOW;
SET COLOR_BODY GREEN;
SET COLOR_NOTE PURPLE;
SET PROP_DISPLAY VALUE;
SET PAGE_NUMBER P51;
SET PATH_NUMBER P68;
FORCEADD Q_CAP..1
(-2525 500);
FORCEPROP 1 LAST VALUE 0.1UF
J 0
(-2475 550);
DISPLAY 0.510638 (-2475 550);
PAINT SKYBLUE (-2475 550);
FORCEPROP 1 LAST TOLERANCE 10%
J 0
(-2475 450);
DISPLAY 0.510638 (-2475 450);
PAINT SKYBLUE (-2475 450);
FORCEPROP 1 LAST PACK_TYPE 0402
J 0
(-2475 300);
DISPLAY 0.510638 (-2475 300);
PAINT SKYBLUE (-2475 300);
FORCEPROP 1 LAST VOLTAGE 25V
J 0
(-2475 500);
DISPLAY 0.510638 (-2475 500);
PAINT SKYBLUE (-2475 500);
FORCEPROP 1 LAST PART_NUMBER CH4104K1B00
J 0
(-2475 350);
DISPLAY 0.510638 (-2475 350);
PAINT WHITE (-2475 350);
FORCEPROP 1 LAST MATERIAL X7R
J 0
(-2475 400);
DISPLAY 0.510638 (-2475 400);
PAINT SKYBLUE (-2475 400);
FORCEPROP 1 LAST PATH I1
J 0
(-2475 650);
DISPLAY 0.978723 (-2475 650);
PAINT WHITE (-2475 650);
DISPLAY INVISIBLE (-2475 650);
FORCEPROP 2 LAST CDS_LIB pure_quanta
J 0
(-2525 500);
DISPLAY INVISIBLE (-2525 500);
FORCEPROP 2 LAST SEC_TYPE 0402
J 0
(-2475 700);
DISPLAY 1.021277 (-2475 700);
DISPLAY INVISIBLE (-2475 700);
FORCEPROP 1 LAST LOCATION PC205
J 0
(-2475 600);
DISPLAY 0.702128 (-2475 600);
PAINT AQUA (-2475 600);
FORCEPROP 1 LASTPIN (-2525 600) $PN 1
J 0
(-2515 580);
DISPLAY 0.808511 (-2515 580);
PAINT WHITE (-2515 580);
FORCEPROP 1 LASTPIN (-2525 400) $PN 2
J 0
(-2515 380);
DISPLAY 0.808511 (-2515 380);
PAINT WHITE (-2515 380);
FORCEPROP 2 LAST SEC 1
J 0
(-2475 700);
DISPLAY 0.680851 (-2475 700);
PAINT MONO (-2475 700);
DISPLAY INVISIBLE (-2475 700);
FORCEADD UNIVERSAL_GND..1
(-1225 300);
FORCEPROP 3 LASTPIN (-1225 350) SIG_NAME GND\g
J 0
(-1215 360);
DISPLAY 0.659574 (-1215 360);
PAINT MONO (-1215 360);
DISPLAY INVISIBLE (-1215 360);
FORCEPROP 1 LAST PATH I10
J 0
(-1150 300);
DISPLAY 0.872340 (-1150 300);
PAINT AQUA (-1150 300);
DISPLAY INVISIBLE (-1150 300);
FORCEPROP 1 LAST HDL_POWER GND
J 1
(-1200 225);
DISPLAY 0.702128 (-1200 225);
PAINT GREEN (-1200 225);
DISPLAY INVISIBLE (-1200 225);
FORCEPROP 2 LAST CDS_LIB logical_power
J 0
(-1225 300);
DISPLAY INVISIBLE (-1225 300);
FORCEADD UNIVERSAL_GND..1
(-650 -275);
FORCEPROP 3 LASTPIN (-650 -225) SIG_NAME GND\g
J 0
(-640 -215);
DISPLAY 0.659574 (-640 -215);
PAINT MONO (-640 -215);
DISPLAY INVISIBLE (-640 -215);
FORCEPROP 1 LAST PATH I12
J 0
(-575 -275);
DISPLAY 0.872340 (-575 -275);
PAINT AQUA (-575 -275);
DISPLAY INVISIBLE (-575 -275);
FORCEPROP 1 LAST HDL_POWER GND
J 1
(-625 -350);
DISPLAY 0.702128 (-625 -350);
PAINT GREEN (-625 -350);
DISPLAY INVISIBLE (-625 -350);
FORCEPROP 2 LAST CDS_LIB logical_power
J 0
(-650 -275);
DISPLAY INVISIBLE (-650 -275);
FORCEADD Q_CAP..1
(-650 25);
FORCEPROP 1 LAST MATERIAL X6S
J 0
(-600 -75);
DISPLAY 0.510638 (-600 -75);
PAINT SKYBLUE (-600 -75);
FORCEPROP 1 LAST VOLTAGE 25V
J 0
(-600 25);
DISPLAY 0.510638 (-600 25);
PAINT SKYBLUE (-600 25);
FORCEPROP 1 LAST TOLERANCE 10%
J 0
(-600 -25);
DISPLAY 0.510638 (-600 -25);
PAINT SKYBLUE (-600 -25);
FORCEPROP 1 LAST VALUE 1UF
J 0
(-600 75);
DISPLAY 0.510638 (-600 75);
PAINT SKYBLUE (-600 75);
FORCEPROP 1 LAST PACK_TYPE C0402
J 0
(-600 -175);
DISPLAY 0.510638 (-600 -175);
PAINT SKYBLUE (-600 -175);
FORCEPROP 1 LAST PART_NUMBER CH5104KEB02
J 0
(-600 -125);
DISPLAY 0.510638 (-600 -125);
PAINT WHITE (-600 -125);
FORCEPROP 1 LAST PATH I13
J 0
(-600 175);
DISPLAY 0.978723 (-600 175);
PAINT WHITE (-600 175);
DISPLAY INVISIBLE (-600 175);
FORCEPROP 2 LAST CDS_LIB pure_quanta
J 0
(-650 25);
DISPLAY INVISIBLE (-650 25);
FORCEPROP 2 LAST SEC_TYPE C0402
J 0
(-600 225);
DISPLAY 1.021277 (-600 225);
DISPLAY INVISIBLE (-600 225);
FORCEPROP 1 LAST LOCATION PC208
J 0
(-600 125);
DISPLAY 0.702128 (-600 125);
PAINT AQUA (-600 125);
FORCEPROP 1 LASTPIN (-650 125) $PN 1
J 0
(-640 105);
DISPLAY 0.808511 (-640 105);
PAINT WHITE (-640 105);
FORCEPROP 1 LASTPIN (-650 -75) $PN 2
J 0
(-640 -95);
DISPLAY 0.808511 (-640 -95);
PAINT WHITE (-640 -95);
FORCEPROP 2 LAST SEC 1
J 0
(-600 225);
DISPLAY 0.680851 (-600 225);
PAINT MONO (-600 225);
DISPLAY INVISIBLE (-600 225);
FORCEADD UNIVERSAL_GND..1
(-1025 1075);
FORCEPROP 3 LASTPIN (-1025 1125) SIG_NAME GND\g
J 0
(-1015 1135);
DISPLAY 0.659574 (-1015 1135);
PAINT MONO (-1015 1135);
DISPLAY INVISIBLE (-1015 1135);
FORCEPROP 1 LAST HDL_POWER GND
J 1
(-1000 1000);
DISPLAY 0.702128 (-1000 1000);
PAINT GREEN (-1000 1000);
DISPLAY INVISIBLE (-1000 1000);
FORCEPROP 1 LAST PATH I14
J 0
(-950 1075);
DISPLAY 0.872340 (-950 1075);
PAINT AQUA (-950 1075);
DISPLAY INVISIBLE (-950 1075);
FORCEPROP 2 LAST CDS_LIB logical_power
J 0
(-1025 1075);
DISPLAY INVISIBLE (-1025 1075);
FORCEADD UNIVERSAL_GND..1
(1475 -425);
FORCEPROP 3 LASTPIN (1475 -375) SIG_NAME GND\g
J 0
(1485 -365);
DISPLAY 0.659574 (1485 -365);
PAINT MONO (1485 -365);
DISPLAY INVISIBLE (1485 -365);
FORCEPROP 1 LAST PATH I19
J 0
(1550 -425);
DISPLAY 0.872340 (1550 -425);
PAINT AQUA (1550 -425);
DISPLAY INVISIBLE (1550 -425);
FORCEPROP 1 LAST HDL_POWER GND
J 1
(1500 -500);
DISPLAY 0.702128 (1500 -500);
PAINT GREEN (1500 -500);
DISPLAY INVISIBLE (1500 -500);
FORCEPROP 2 LAST CDS_LIB logical_power
J 0
(1475 -425);
DISPLAY INVISIBLE (1475 -425);
FORCEADD UNIVERSAL_GND..1
(-2075 100);
FORCEPROP 3 LASTPIN (-2075 150) SIG_NAME GND\g
J 0
(-2065 160);
DISPLAY 0.659574 (-2065 160);
PAINT MONO (-2065 160);
DISPLAY INVISIBLE (-2065 160);
FORCEPROP 1 LAST PATH I2
J 0
(-2000 100);
DISPLAY 0.872340 (-2000 100);
PAINT AQUA (-2000 100);
DISPLAY INVISIBLE (-2000 100);
FORCEPROP 1 LAST HDL_POWER GND
J 1
(-2050 25);
DISPLAY 0.702128 (-2050 25);
PAINT GREEN (-2050 25);
DISPLAY INVISIBLE (-2050 25);
FORCEPROP 2 LAST CDS_LIB logical_power
J 0
(-2075 100);
DISPLAY INVISIBLE (-2075 100);
FORCEADD UNIVERSAL_GND..1
(1750 -700);
FORCEPROP 3 LASTPIN (1750 -650) SIG_NAME GND\g
J 0
(1760 -640);
DISPLAY 0.659574 (1760 -640);
PAINT MONO (1760 -640);
DISPLAY INVISIBLE (1760 -640);
FORCEPROP 1 LAST PATH I20
J 0
(1825 -700);
DISPLAY 0.872340 (1825 -700);
PAINT AQUA (1825 -700);
DISPLAY INVISIBLE (1825 -700);
FORCEPROP 1 LAST HDL_POWER GND
J 1
(1775 -775);
DISPLAY 0.702128 (1775 -775);
PAINT GREEN (1775 -775);
DISPLAY INVISIBLE (1775 -775);
FORCEPROP 2 LAST CDS_LIB logical_power
J 0
(1750 -700);
DISPLAY INVISIBLE (1750 -700);
FORCEADD Q_RES..2
(2825 1450);
FORCEPROP 1 LAST WATTAGE 1/16W
J 0
(2865 1425);
DISPLAY 0.510638 (2865 1425);
PAINT SKYBLUE (2865 1425);
FORCEPROP 1 LAST MATERIAL CHIP
J 0
(2865 1375);
DISPLAY 0.510638 (2865 1375);
PAINT SKYBLUE (2865 1375);
FORCEPROP 1 LAST PART_NUMBER CS31002FB08
J 0
(2865 1325);
DISPLAY 0.510638 (2865 1325);
PAINT WHITE (2865 1325);
FORCEPROP 1 LAST PACK_TYPE 0402LF
J 0
(2865 1275);
DISPLAY 0.510638 (2865 1275);
PAINT SKYBLUE (2865 1275);
FORCEPROP 1 LAST VALUE 10K
J 0
(2870 1525);
DISPLAY 0.510638 (2870 1525);
PAINT SKYBLUE (2870 1525);
FORCEPROP 1 LAST TOLERANCE 1%
J 0
(2870 1475);
DISPLAY 0.510638 (2870 1475);
PAINT SKYBLUE (2870 1475);
FORCEPROP 2 LAST SEC_TYPE 0402LF
J 0
(2875 1675);
DISPLAY 0.680851 (2875 1675);
DISPLAY INVISIBLE (2875 1675);
FORCEPROP 2 LAST CDS_LIB pure_quanta
J 0
(2825 1450);
DISPLAY INVISIBLE (2825 1450);
FORCEPROP 1 LAST PATH I21
J 0
(2875 1625);
DISPLAY 0.978723 (2875 1625);
PAINT WHITE (2875 1625);
DISPLAY INVISIBLE (2875 1625);
FORCEPROP 1 LAST LOCATION PR241
J 0
(2870 1575);
DISPLAY 0.702128 (2870 1575);
PAINT AQUA (2870 1575);
FORCEPROP 1 LASTPIN (2825 1550) $PN 1
J 0
(2830 1512);
DISPLAY 0.808511 (2830 1512);
PAINT WHITE (2830 1512);
FORCEPROP 1 LASTPIN (2825 1350) $PN 2
J 0
(2830 1360);
DISPLAY 0.808511 (2830 1360);
PAINT WHITE (2830 1360);
FORCEPROP 2 LAST SEC 1
J 0
(2875 1675);
DISPLAY 0.680851 (2875 1675);
PAINT MONO (2875 1675);
DISPLAY INVISIBLE (2875 1675);
FORCEADD Q_CAP..1
(1750 -275);
FORCEPROP 1 LAST PACK_TYPE 0402
J 0
(1800 -475);
DISPLAY 0.510638 (1800 -475);
PAINT SKYBLUE (1800 -475);
FORCEPROP 1 LAST PART_NUMBER CH4104K1B00
J 0
(1800 -425);
DISPLAY 0.510638 (1800 -425);
PAINT WHITE (1800 -425);
FORCEPROP 1 LAST VALUE 0.1UF
J 0
(1800 -225);
DISPLAY 0.510638 (1800 -225);
PAINT SKYBLUE (1800 -225);
FORCEPROP 1 LAST VOLTAGE 25V
J 0
(1800 -275);
DISPLAY 0.510638 (1800 -275);
PAINT SKYBLUE (1800 -275);
FORCEPROP 1 LAST MATERIAL X7R
J 0
(1800 -375);
DISPLAY 0.510638 (1800 -375);
PAINT SKYBLUE (1800 -375);
FORCEPROP 1 LAST TOLERANCE 10%
J 0
(1800 -325);
DISPLAY 0.510638 (1800 -325);
PAINT SKYBLUE (1800 -325);
FORCEPROP 1 LAST PATH I22
J 0
(1800 -125);
DISPLAY 0.978723 (1800 -125);
PAINT WHITE (1800 -125);
DISPLAY INVISIBLE (1800 -125);
FORCEPROP 2 LAST CDS_LIB pure_quanta
J 0
(1750 -275);
DISPLAY INVISIBLE (1750 -275);
FORCEPROP 1 LAST LOCATION PC271
J 0
(1800 -175);
DISPLAY 0.702128 (1800 -175);
PAINT AQUA (1800 -175);
FORCEPROP 0 LAST $SEC 1
J 0
(1800 -125);
DISPLAY 0.680851 (1800 -125);
PAINT MONO (1800 -125);
DISPLAY INVISIBLE (1800 -125);
FORCEPROP 0 LAST CDS_SEC 1
J 0
(1800 -125);
DISPLAY 1.021277 (1800 -125);
DISPLAY INVISIBLE (1800 -125);
FORCEPROP 1 LASTPIN (1750 -175) $PN 1
J 0
(1760 -195);
DISPLAY 0.808511 (1760 -195);
PAINT WHITE (1760 -195);
DISPLAY INVISIBLE (1760 -195);
FORCEPROP 1 LASTPIN (1750 -375) $PN 2
J 0
(1760 -395);
DISPLAY 0.808511 (1760 -395);
PAINT WHITE (1760 -395);
DISPLAY INVISIBLE (1760 -395);
FORCEADD Q_CAP..1
(1975 825);
FORCEPROP 1 LAST VOLTAGE 16V
J 0
(2050 900);
DISPLAY 0.510638 (2050 900);
PAINT SKYBLUE (2050 900);
FORCEPROP 1 LAST VALUE 0.22UF
J 0
(2050 950);
DISPLAY 0.510638 (2050 950);
PAINT SKYBLUE (2050 950);
FORCEPROP 1 LAST MATERIAL X7R
J 0
(2050 800);
DISPLAY 0.510638 (2050 800);
PAINT SKYBLUE (2050 800);
FORCEPROP 1 LAST TOLERANCE 10%
J 0
(2050 850);
DISPLAY 0.510638 (2050 850);
PAINT SKYBLUE (2050 850);
FORCEPROP 1 LAST PART_NUMBER CH4223K1B00
J 0
(2050 750);
DISPLAY 0.510638 (2050 750);
PAINT WHITE (2050 750);
FORCEPROP 1 LAST PACK_TYPE 0402
J 0
(2050 700);
DISPLAY 0.510638 (2050 700);
PAINT SKYBLUE (2050 700);
FORCEPROP 1 LAST PATH I23
J 0
(2025 975);
DISPLAY 0.978723 (2025 975);
PAINT WHITE (2025 975);
DISPLAY INVISIBLE (2025 975);
FORCEPROP 2 LAST SEC_TYPE 0402
J 0
(2025 1025);
DISPLAY 1.021277 (2025 1025);
DISPLAY INVISIBLE (2025 1025);
FORCEPROP 2 LAST CDS_LIB pure_quanta
J 0
(1975 825);
DISPLAY INVISIBLE (1975 825);
FORCEPROP 1 LAST LOCATION PC216
J 0
(2050 1000);
DISPLAY 0.702128 (2050 1000);
PAINT AQUA (2050 1000);
FORCEPROP 1 LASTPIN (1975 925) $PN 1
J 0
(1985 905);
DISPLAY 0.808511 (1985 905);
PAINT WHITE (1985 905);
FORCEPROP 1 LASTPIN (1975 725) $PN 2
J 0
(1985 705);
DISPLAY 0.808511 (1985 705);
PAINT WHITE (1985 705);
FORCEPROP 2 LAST SEC 1
J 0
(2025 1025);
DISPLAY 0.680851 (2025 1025);
PAINT MONO (2025 1025);
DISPLAY INVISIBLE (2025 1025);
FORCEADD VCCAUX15..1
(2825 1725);
FORCEPROP 3 LASTPIN (2825 1675) SIG_NAME P5V_AUX_VCC\g
J 0
(2835 1685);
DISPLAY 0.659574 (2835 1685);
PAINT MONO (2835 1685);
DISPLAY INVISIBLE (2835 1685);
FORCEPROP 1 LAST HDL_POWER P5V_AUX_VCC
J 1
(2825 1775);
DISPLAY 0.702128 (2825 1775);
PAINT GREEN (2825 1775);
FORCEPROP 1 LAST PATH I24
J 0
(2875 1750);
DISPLAY 0.872340 (2875 1750);
PAINT AQUA (2875 1750);
DISPLAY INVISIBLE (2875 1750);
FORCEPROP 2 LAST CDS_LIB logical_power
J 0
(2825 1725);
DISPLAY INVISIBLE (2825 1725);
FORCEADD UNIVERSAL_GND..1
(2850 -600);
FORCEPROP 3 LASTPIN (2850 -550) SIG_NAME GND\g
J 0
(2860 -540);
DISPLAY 0.659574 (2860 -540);
PAINT MONO (2860 -540);
DISPLAY INVISIBLE (2860 -540);
FORCEPROP 1 LAST PATH I25
J 0
(2925 -600);
DISPLAY 0.872340 (2925 -600);
PAINT AQUA (2925 -600);
DISPLAY INVISIBLE (2925 -600);
FORCEPROP 1 LAST HDL_POWER GND
J 1
(2875 -675);
DISPLAY 0.702128 (2875 -675);
PAINT GREEN (2875 -675);
DISPLAY INVISIBLE (2875 -675);
FORCEPROP 2 LAST CDS_LIB logical_power
J 0
(2850 -600);
DISPLAY INVISIBLE (2850 -600);
FORCEADD Q_RES..2
(2850 -325);
FORCEPROP 1 LAST PACK_TYPE 0402LF
J 0
(2890 -500);
DISPLAY 0.510638 (2890 -500);
PAINT SKYBLUE (2890 -500);
FORCEPROP 1 LAST PART_NUMBER CS31242FB02
J 0
(2890 -450);
DISPLAY 0.510638 (2890 -450);
PAINT WHITE (2890 -450);
FORCEPROP 1 LAST MATERIAL CHIP
J 0
(2890 -400);
DISPLAY 0.510638 (2890 -400);
PAINT SKYBLUE (2890 -400);
FORCEPROP 1 LAST WATTAGE 1/16W
J 0
(2890 -350);
DISPLAY 0.510638 (2890 -350);
PAINT SKYBLUE (2890 -350);
FORCEPROP 1 LAST TOLERANCE 1%
J 0
(2895 -300);
DISPLAY 0.510638 (2895 -300);
PAINT SKYBLUE (2895 -300);
FORCEPROP 1 LAST VALUE 12.4K
J 0
(2895 -250);
DISPLAY 0.510638 (2895 -250);
PAINT SKYBLUE (2895 -250);
FORCEPROP 1 LAST PATH I26
J 0
(2900 -150);
DISPLAY 0.978723 (2900 -150);
PAINT WHITE (2900 -150);
DISPLAY INVISIBLE (2900 -150);
FORCEPROP 2 LAST CDS_LIB pure_quanta
J 0
(2850 -325);
DISPLAY INVISIBLE (2850 -325);
FORCEPROP 1 LAST LOCATION PR526
J 0
(2895 -200);
DISPLAY 0.702128 (2895 -200);
PAINT AQUA (2895 -200);
FORCEPROP 0 LAST $SEC 1
J 0
(2900 -150);
DISPLAY 0.680851 (2900 -150);
PAINT MONO (2900 -150);
DISPLAY INVISIBLE (2900 -150);
FORCEPROP 0 LAST CDS_SEC 1
J 0
(2900 -150);
DISPLAY 1.021277 (2900 -150);
DISPLAY INVISIBLE (2900 -150);
FORCEPROP 1 LASTPIN (2850 -225) $PN 1
J 0
(2855 -263);
DISPLAY 0.808511 (2855 -263);
PAINT WHITE (2855 -263);
DISPLAY INVISIBLE (2855 -263);
FORCEPROP 1 LASTPIN (2850 -425) $PN 2
J 0
(2855 -415);
DISPLAY 0.808511 (2855 -415);
PAINT WHITE (2855 -415);
DISPLAY INVISIBLE (2855 -415);
FORCEADD Q_CAP..2
(4100 -500);
FORCEPROP 1 LAST PART_NUMBER CH06806JB01
J 1
(4100 -450);
DISPLAY 0.510638 (4100 -450);
PAINT WHITE (4100 -450);
FORCEPROP 1 LAST TOLERANCE 5%
J 2
(4100 -650);
DISPLAY 0.510638 (4100 -650);
PAINT SKYBLUE (4100 -650);
FORCEPROP 1 LAST MATERIAL COG
J 0
(4100 -650);
DISPLAY 0.510638 (4100 -650);
PAINT SKYBLUE (4100 -650);
FORCEPROP 1 LAST VOLTAGE 50V
J 0
(4100 -600);
DISPLAY 0.510638 (4100 -600);
PAINT SKYBLUE (4100 -600);
FORCEPROP 1 LAST PACK_TYPE C0402
J 1
(4100 -700);
DISPLAY 0.510638 (4100 -700);
PAINT SKYBLUE (4100 -700);
FORCEPROP 1 LAST VALUE 68PF
J 2
(4100 -600);
DISPLAY 0.510638 (4100 -600);
PAINT SKYBLUE (4100 -600);
FORCEPROP 1 LAST PATH I27
J 0
(4100 -300);
DISPLAY 0.978723 (4100 -300);
PAINT WHITE (4100 -300);
DISPLAY INVISIBLE (4100 -300);
FORCEPROP 2 LAST CDS_LIB pure_quanta
J 0
(4100 -500);
DISPLAY INVISIBLE (4100 -500);
FORCEPROP 1 LAST LOCATION PC272
J 1
(4100 -400);
DISPLAY 0.702128 (4100 -400);
PAINT AQUA (4100 -400);
FORCEPROP 0 LAST $SEC 1
J 0
(4100 -350);
DISPLAY 0.680851 (4100 -350);
PAINT MONO (4100 -350);
DISPLAY INVISIBLE (4100 -350);
FORCEPROP 0 LAST CDS_SEC 1
J 0
(4100 -350);
DISPLAY 1.021277 (4100 -350);
DISPLAY INVISIBLE (4100 -350);
FORCEPROP 1 LASTPIN (4000 -500) $PN 1
J 0
(3990 -485);
DISPLAY 0.808511 (3990 -485);
PAINT WHITE (3990 -485);
DISPLAY INVISIBLE (3990 -485);
FORCEPROP 1 LASTPIN (4200 -500) $PN 2
J 0
(4185 -485);
DISPLAY 0.808511 (4185 -485);
PAINT WHITE (4185 -485);
DISPLAY INVISIBLE (4185 -485);
FORCEADD Q_INDUCTOR..1
(3250 700);
FORCEPROP 1 LAST PART_NUMBER CV-47A0MZ10
J 0
(3125 810);
DISPLAY 0.510638 (3125 810);
PAINT WHITE (3125 810);
FORCEPROP 2 LAST VALUE 4.7UH
J 0
(3175 600);
DISPLAY 0.510638 (3175 600);
PAINT SKYBLUE (3175 600);
FORCEPROP 1 LAST MATERIAL IND
J 0
(3125 755);
DISPLAY 0.510638 (3125 755);
PAINT SKYBLUE (3125 755);
FORCEPROP 0 LAST R1 DCR=13.2MOHM
J 0
(2875 525);
DISPLAY 0.638298 (2875 525);
PAINT WHITE (2875 525);
FORCEPROP 2 LAST PACK_TYPE SMLF
J 0
(3050 600);
DISPLAY 0.510638 (3050 600);
PAINT SKYBLUE (3050 600);
FORCEPROP 0 LAST R3 ISAT=13A
J 0
(2875 425);
DISPLAY 0.638298 (2875 425);
PAINT WHITE (2875 425);
FORCEPROP 1 LAST PATH I28
J 0
(3325 755);
DISPLAY 0.723404 (3325 755);
PAINT GREEN (3325 755);
DISPLAY INVISIBLE (3325 755);
FORCEPROP 2 LAST CDS_LIB pure_quanta
J 0
(3250 700);
DISPLAY INVISIBLE (3250 700);
FORCEPROP 1 LAST NEEDS_NO_SIZE TRUE
J 0
(3250 700);
DISPLAY 0.468085 (3250 700);
PAINT GREEN (3250 700);
DISPLAY INVISIBLE (3250 700);
FORCEPROP 1 LAST LOCATION PL34
J 0
(3125 860);
DISPLAY 0.702128 (3125 860);
PAINT AQUA (3125 860);
FORCEPROP 0 LASTPIN (3150 675) $PN 1
J 2
(3140 685);
DISPLAY 0.680851 (3140 685);
PAINT MONO (3140 685);
FORCEPROP 0 LASTPIN (3350 675) $PN 2
J 0
(3360 685);
DISPLAY 0.680851 (3360 685);
PAINT MONO (3360 685);
FORCEPROP 0 LAST $SEC 1
J 0
(3125 900);
DISPLAY 0.680851 (3125 900);
PAINT MONO (3125 900);
DISPLAY INVISIBLE (3125 900);
FORCEPROP 0 LAST CDS_SEC 1
J 0
(3125 900);
DISPLAY 1.021277 (3125 900);
DISPLAY INVISIBLE (3125 900);
FORCEADD Q_RES..2
(-2075 500);
FORCEPROP 1 LAST VALUE 100K
J 0
(-2030 575);
DISPLAY 0.510638 (-2030 575);
PAINT SKYBLUE (-2030 575);
FORCEPROP 1 LAST PACK_TYPE 0402LF
J 0
(-2035 325);
DISPLAY 0.510638 (-2035 325);
PAINT SKYBLUE (-2035 325);
FORCEPROP 1 LAST MATERIAL CHIP
J 0
(-2035 425);
DISPLAY 0.510638 (-2035 425);
PAINT SKYBLUE (-2035 425);
FORCEPROP 1 LAST WATTAGE 1/16W
J 0
(-2035 475);
DISPLAY 0.510638 (-2035 475);
PAINT SKYBLUE (-2035 475);
FORCEPROP 1 LAST TOLERANCE 1%
J 0
(-2030 525);
DISPLAY 0.510638 (-2030 525);
PAINT SKYBLUE (-2030 525);
FORCEPROP 1 LAST PART_NUMBER CS41002FB09
J 0
(-2035 375);
DISPLAY 0.510638 (-2035 375);
PAINT WHITE (-2035 375);
FORCEPROP 1 LAST PATH I3
J 0
(-2025 675);
DISPLAY 0.978723 (-2025 675);
PAINT WHITE (-2025 675);
DISPLAY INVISIBLE (-2025 675);
FORCEPROP 2 LAST CDS_LIB pure_quanta
J 0
(-2075 500);
DISPLAY INVISIBLE (-2075 500);
FORCEPROP 1 LAST LOCATION PR522
J 0
(-2030 625);
DISPLAY 0.702128 (-2030 625);
PAINT AQUA (-2030 625);
FORCEPROP 0 LAST $SEC 1
J 0
(-2025 675);
DISPLAY 0.680851 (-2025 675);
PAINT MONO (-2025 675);
DISPLAY INVISIBLE (-2025 675);
FORCEPROP 0 LAST CDS_SEC 1
J 0
(-2025 675);
DISPLAY 1.021277 (-2025 675);
DISPLAY INVISIBLE (-2025 675);
FORCEPROP 1 LASTPIN (-2075 600) $PN 1
J 0
(-2070 562);
DISPLAY 0.808511 (-2070 562);
PAINT WHITE (-2070 562);
DISPLAY INVISIBLE (-2070 562);
FORCEPROP 1 LASTPIN (-2075 400) $PN 2
J 0
(-2070 410);
DISPLAY 0.808511 (-2070 410);
PAINT WHITE (-2070 410);
DISPLAY INVISIBLE (-2070 410);
FORCEADD Q_RES..1
(4100 -150);
FORCEPROP 1 LAST VALUE 91K
J 2
(4075 -250);
DISPLAY 0.510638 (4075 -250);
PAINT SKYBLUE (4075 -250);
FORCEPROP 1 LAST TOLERANCE 1%
J 0
(4100 -250);
DISPLAY 0.510638 (4100 -250);
PAINT SKYBLUE (4100 -250);
FORCEPROP 1 LAST PART_NUMBER CS39102FB06
J 0
(4200 -250);
DISPLAY 0.510638 (4200 -250);
PAINT WHITE (4200 -250);
FORCEPROP 1 LAST PACK_TYPE 0402LF
J 0
(4350 -300);
DISPLAY 0.510638 (4350 -300);
PAINT SKYBLUE (4350 -300);
FORCEPROP 1 LAST MATERIAL CHIP
J 0
(4100 -300);
DISPLAY 0.510638 (4100 -300);
PAINT SKYBLUE (4100 -300);
FORCEPROP 1 LAST WATTAGE 1/16W
J 2
(4075 -300);
DISPLAY 0.510638 (4075 -300);
PAINT SKYBLUE (4075 -300);
FORCEPROP 1 LAST PATH I30
J 0
(4050 0);
DISPLAY 0.978723 (4050 0);
PAINT WHITE (4050 0);
DISPLAY INVISIBLE (4050 0);
FORCEPROP 2 LAST CDS_LIB pure_quanta
J 0
(4100 -150);
DISPLAY INVISIBLE (4100 -150);
FORCEPROP 1 LAST LOCATION PR527
J 0
(4050 -100);
DISPLAY 0.702128 (4050 -100);
PAINT AQUA (4050 -100);
FORCEPROP 0 LAST $SEC 1
J 0
(4050 -50);
DISPLAY 0.680851 (4050 -50);
PAINT MONO (4050 -50);
DISPLAY INVISIBLE (4050 -50);
FORCEPROP 0 LAST CDS_SEC 1
J 0
(4050 -25);
DISPLAY 1.021277 (4050 -25);
DISPLAY INVISIBLE (4050 -25);
FORCEPROP 1 LASTPIN (4000 -150) $PN 1
J 0
(4012 -138);
DISPLAY 0.808511 (4012 -138);
PAINT WHITE (4012 -138);
DISPLAY INVISIBLE (4012 -138);
FORCEPROP 1 LASTPIN (4200 -150) $PN 2
J 0
(4162 -138);
DISPLAY 0.808511 (4162 -138);
PAINT WHITE (4162 -138);
DISPLAY INVISIBLE (4162 -138);
FORCEADD Q_CAP..1
(3725 425);
FORCEPROP 1 LAST PACK_TYPE 0402
J 0
(3775 225);
DISPLAY 0.510638 (3775 225);
PAINT SKYBLUE (3775 225);
FORCEPROP 1 LAST PART_NUMBER CH4104K1B00
J 0
(3775 275);
DISPLAY 0.510638 (3775 275);
PAINT WHITE (3775 275);
FORCEPROP 1 LAST VALUE 0.1UF
J 0
(3775 475);
DISPLAY 0.510638 (3775 475);
PAINT SKYBLUE (3775 475);
FORCEPROP 1 LAST VOLTAGE 25V
J 0
(3775 425);
DISPLAY 0.510638 (3775 425);
PAINT SKYBLUE (3775 425);
FORCEPROP 1 LAST TOLERANCE 10%
J 0
(3775 375);
DISPLAY 0.510638 (3775 375);
PAINT SKYBLUE (3775 375);
FORCEPROP 1 LAST MATERIAL X7R
J 0
(3775 325);
DISPLAY 0.510638 (3775 325);
PAINT SKYBLUE (3775 325);
FORCEPROP 1 LAST PATH I31
J 0
(3775 575);
DISPLAY 0.978723 (3775 575);
PAINT WHITE (3775 575);
DISPLAY INVISIBLE (3775 575);
FORCEPROP 2 LAST SEC_TYPE 0402
J 0
(3775 625);
DISPLAY 1.021277 (3775 625);
DISPLAY INVISIBLE (3775 625);
FORCEPROP 2 LAST CDS_LIB pure_quanta
J 0
(3725 425);
DISPLAY INVISIBLE (3725 425);
FORCEPROP 1 LAST LOCATION PC212
J 0
(3775 525);
DISPLAY 0.702128 (3775 525);
PAINT AQUA (3775 525);
FORCEPROP 1 LASTPIN (3725 525) $PN 1
J 0
(3735 505);
DISPLAY 0.808511 (3735 505);
PAINT WHITE (3735 505);
FORCEPROP 1 LASTPIN (3725 325) $PN 2
J 0
(3735 305);
DISPLAY 0.808511 (3735 305);
PAINT WHITE (3735 305);
FORCEPROP 2 LAST SEC 1
J 0
(3775 625);
DISPLAY 0.680851 (3775 625);
PAINT MONO (3775 625);
DISPLAY INVISIBLE (3775 625);
FORCEADD Q_CAP..1
(4150 425);
FORCEPROP 1 LAST VALUE 22UF
J 0
(4200 475);
DISPLAY 0.510638 (4200 475);
PAINT SKYBLUE (4200 475);
FORCEPROP 1 LAST VOLTAGE 10V
J 0
(4200 425);
DISPLAY 0.510638 (4200 425);
PAINT SKYBLUE (4200 425);
FORCEPROP 1 LAST PART_NUMBER CH6222MEA00
J 0
(4200 275);
DISPLAY 0.510638 (4200 275);
PAINT WHITE (4200 275);
FORCEPROP 1 LAST PACK_TYPE C0805
J 0
(4200 225);
DISPLAY 0.510638 (4200 225);
PAINT SKYBLUE (4200 225);
FORCEPROP 1 LAST TOLERANCE 20%
J 0
(4200 375);
DISPLAY 0.510638 (4200 375);
PAINT SKYBLUE (4200 375);
FORCEPROP 1 LAST MATERIAL X6S
J 0
(4200 325);
DISPLAY 0.510638 (4200 325);
PAINT SKYBLUE (4200 325);
FORCEPROP 1 LAST PATH I32
J 0
(4200 575);
DISPLAY 0.978723 (4200 575);
PAINT WHITE (4200 575);
DISPLAY INVISIBLE (4200 575);
FORCEPROP 2 LAST CDS_LIB pure_quanta
J 0
(4150 425);
DISPLAY INVISIBLE (4150 425);
FORCEPROP 1 LAST LOCATION PC213
J 0
(4200 525);
DISPLAY 0.702128 (4200 525);
PAINT AQUA (4200 525);
FORCEPROP 1 LASTPIN (4150 525) $PN 1
J 0
(4160 505);
DISPLAY 0.808511 (4160 505);
PAINT WHITE (4160 505);
FORCEPROP 1 LASTPIN (4150 325) $PN 2
J 0
(4160 305);
DISPLAY 0.808511 (4160 305);
PAINT WHITE (4160 305);
FORCEPROP 0 LAST $SEC 1
J 0
(4200 575);
DISPLAY 0.680851 (4200 575);
PAINT MONO (4200 575);
DISPLAY INVISIBLE (4200 575);
FORCEPROP 0 LAST CDS_SEC 1
J 0
(4200 575);
DISPLAY 1.021277 (4200 575);
DISPLAY INVISIBLE (4200 575);
FORCEADD Q_CAP..1
(4500 425);
FORCEPROP 1 LAST VALUE 22UF
J 0
(4550 475);
DISPLAY 0.510638 (4550 475);
PAINT SKYBLUE (4550 475);
FORCEPROP 1 LAST VOLTAGE 10V
J 0
(4550 425);
DISPLAY 0.510638 (4550 425);
PAINT SKYBLUE (4550 425);
FORCEPROP 1 LAST TOLERANCE 20%
J 0
(4550 375);
DISPLAY 0.510638 (4550 375);
PAINT SKYBLUE (4550 375);
FORCEPROP 1 LAST MATERIAL X6S
J 0
(4550 325);
DISPLAY 0.510638 (4550 325);
PAINT SKYBLUE (4550 325);
FORCEPROP 1 LAST PART_NUMBER CH6222MEA00
J 0
(4550 275);
DISPLAY 0.510638 (4550 275);
PAINT WHITE (4550 275);
FORCEPROP 1 LAST PACK_TYPE C0805
J 0
(4550 225);
DISPLAY 0.510638 (4550 225);
PAINT SKYBLUE (4550 225);
FORCEPROP 1 LAST PATH I33
J 0
(4550 575);
DISPLAY 0.978723 (4550 575);
PAINT WHITE (4550 575);
DISPLAY INVISIBLE (4550 575);
FORCEPROP 2 LAST CDS_LIB pure_quanta
J 0
(4500 425);
DISPLAY INVISIBLE (4500 425);
FORCEPROP 1 LAST LOCATION PC214
J 0
(4550 525);
DISPLAY 0.702128 (4550 525);
PAINT AQUA (4550 525);
FORCEPROP 1 LASTPIN (4500 525) $PN 1
J 0
(4510 505);
DISPLAY 0.808511 (4510 505);
PAINT WHITE (4510 505);
FORCEPROP 1 LASTPIN (4500 325) $PN 2
J 0
(4510 305);
DISPLAY 0.808511 (4510 305);
PAINT WHITE (4510 305);
FORCEPROP 0 LAST $SEC 1
J 0
(4550 575);
DISPLAY 0.680851 (4550 575);
PAINT MONO (4550 575);
DISPLAY INVISIBLE (4550 575);
FORCEPROP 0 LAST CDS_SEC 1
J 0
(4550 575);
DISPLAY 1.021277 (4550 575);
DISPLAY INVISIBLE (4550 575);
FORCEADD UNIVERSAL_GND..1
(5025 100);
FORCEPROP 3 LASTPIN (5025 150) SIG_NAME GND\g
J 0
(5035 160);
DISPLAY 0.659574 (5035 160);
PAINT MONO (5035 160);
DISPLAY INVISIBLE (5035 160);
FORCEPROP 1 LAST PATH I35
J 0
(5100 100);
DISPLAY 0.872340 (5100 100);
PAINT AQUA (5100 100);
DISPLAY INVISIBLE (5100 100);
FORCEPROP 1 LAST HDL_POWER GND
J 1
(5050 25);
DISPLAY 0.702128 (5050 25);
PAINT GREEN (5050 25);
DISPLAY INVISIBLE (5050 25);
FORCEPROP 2 LAST CDS_LIB logical_power
J 0
(5025 100);
DISPLAY INVISIBLE (5025 100);
FORCEADD Q_CAP..1
(4825 425);
FORCEPROP 1 LAST PACK_TYPE C0805
J 0
(4875 225);
DISPLAY 0.510638 (4875 225);
PAINT SKYBLUE (4875 225);
FORCEPROP 1 LAST PART_NUMBER CH6222MEA00
J 0
(4875 275);
DISPLAY 0.510638 (4875 275);
PAINT WHITE (4875 275);
FORCEPROP 1 LAST VALUE 22UF
J 0
(4875 475);
DISPLAY 0.510638 (4875 475);
PAINT SKYBLUE (4875 475);
FORCEPROP 1 LAST TOLERANCE 20%
J 0
(4875 375);
DISPLAY 0.510638 (4875 375);
PAINT SKYBLUE (4875 375);
FORCEPROP 1 LAST MATERIAL X6S
J 0
(4875 325);
DISPLAY 0.510638 (4875 325);
PAINT SKYBLUE (4875 325);
FORCEPROP 1 LAST VOLTAGE 10V
J 0
(4875 425);
DISPLAY 0.510638 (4875 425);
PAINT SKYBLUE (4875 425);
FORCEPROP 1 LAST PATH I36
J 0
(4875 575);
DISPLAY 0.978723 (4875 575);
PAINT WHITE (4875 575);
DISPLAY INVISIBLE (4875 575);
FORCEPROP 2 LAST CDS_LIB pure_quanta
J 0
(4825 425);
DISPLAY INVISIBLE (4825 425);
FORCEPROP 1 LAST LOCATION PC215
J 0
(4875 525);
DISPLAY 0.702128 (4875 525);
PAINT AQUA (4875 525);
FORCEPROP 1 LASTPIN (4825 525) $PN 1
J 0
(4835 505);
DISPLAY 0.808511 (4835 505);
PAINT WHITE (4835 505);
FORCEPROP 1 LASTPIN (4825 325) $PN 2
J 0
(4835 305);
DISPLAY 0.808511 (4835 305);
PAINT WHITE (4835 305);
FORCEPROP 0 LAST $SEC 1
J 0
(4875 575);
DISPLAY 0.680851 (4875 575);
PAINT MONO (4875 575);
DISPLAY INVISIBLE (4875 575);
FORCEPROP 0 LAST CDS_SEC 1
J 0
(4875 575);
DISPLAY 1.021277 (4875 575);
DISPLAY INVISIBLE (4875 575);
FORCEADD Q_CAP..1
(5175 425);
FORCEPROP 1 LAST VALUE 22UF
J 0
(5225 475);
DISPLAY 0.510638 (5225 475);
PAINT SKYBLUE (5225 475);
FORCEPROP 1 LAST PACK_TYPE C0805
J 0
(5225 225);
DISPLAY 0.510638 (5225 225);
PAINT SKYBLUE (5225 225);
FORCEPROP 1 LAST PART_NUMBER CH6222MEA00
J 0
(5225 275);
DISPLAY 0.510638 (5225 275);
PAINT WHITE (5225 275);
FORCEPROP 1 LAST TOLERANCE 20%
J 0
(5225 375);
DISPLAY 0.510638 (5225 375);
PAINT SKYBLUE (5225 375);
FORCEPROP 1 LAST MATERIAL X6S
J 0
(5225 325);
DISPLAY 0.510638 (5225 325);
PAINT SKYBLUE (5225 325);
FORCEPROP 1 LAST VOLTAGE 10V
J 0
(5225 425);
DISPLAY 0.510638 (5225 425);
PAINT SKYBLUE (5225 425);
FORCEPROP 1 LAST PATH I37
J 0
(5225 575);
DISPLAY 0.978723 (5225 575);
PAINT WHITE (5225 575);
DISPLAY INVISIBLE (5225 575);
FORCEPROP 2 LAST CDS_LIB pure_quanta
J 0
(5175 425);
DISPLAY INVISIBLE (5175 425);
FORCEPROP 1 LAST LOCATION PC217
J 0
(5225 525);
DISPLAY 0.702128 (5225 525);
PAINT AQUA (5225 525);
FORCEPROP 1 LASTPIN (5175 525) $PN 1
J 0
(5185 505);
DISPLAY 0.808511 (5185 505);
PAINT WHITE (5185 505);
FORCEPROP 1 LASTPIN (5175 325) $PN 2
J 0
(5185 305);
DISPLAY 0.808511 (5185 305);
PAINT WHITE (5185 305);
FORCEPROP 0 LAST $SEC 1
J 0
(5225 575);
DISPLAY 0.680851 (5225 575);
PAINT MONO (5225 575);
DISPLAY INVISIBLE (5225 575);
FORCEPROP 0 LAST CDS_SEC 1
J 0
(5225 575);
DISPLAY 1.021277 (5225 575);
DISPLAY INVISIBLE (5225 575);
FORCEADD VCCAUX15..1
(5675 800);
FORCEPROP 3 LASTPIN (5675 750) SIG_NAME P5V_AUX\g
J 0
(5685 760);
DISPLAY 0.659574 (5685 760);
PAINT MONO (5685 760);
DISPLAY INVISIBLE (5685 760);
FORCEPROP 1 LAST HDL_POWER P5V_AUX
J 1
(5675 850);
DISPLAY 0.702128 (5675 850);
PAINT GREEN (5675 850);
FORCEPROP 1 LAST PATH I38
J 0
(5725 825);
DISPLAY 0.872340 (5725 825);
PAINT AQUA (5725 825);
DISPLAY INVISIBLE (5725 825);
FORCEPROP 2 LAST CDS_LIB logical_power
J 0
(5675 800);
DISPLAY INVISIBLE (5675 800);
FORCEADD Q_INDUCTOR..1
(-1775 1675);
FORCEPROP 1 LAST PART_NUMBER CX220TN1001
J 0
(-1975 1600);
DISPLAY 0.510638 (-1975 1600);
PAINT WHITE (-1975 1600);
FORCEPROP 2 LAST PACK_TYPE SMLF
J 0
(-1875 1450);
DISPLAY 0.510638 (-1875 1450);
PAINT SKYBLUE (-1875 1450);
FORCEPROP 1 LAST MATERIAL IND
J 0
(-1875 1550);
DISPLAY 0.510638 (-1875 1550);
PAINT SKYBLUE (-1875 1550);
FORCEPROP 2 LAST VALUE BLM18SN220TN1D/8000MA
J 0
(-2075 1500);
DISPLAY 0.510638 (-2075 1500);
PAINT SKYBLUE (-2075 1500);
FORCEPROP 1 LAST NEEDS_NO_SIZE TRUE
J 0
(-1775 1675);
DISPLAY 0.468085 (-1775 1675);
PAINT GREEN (-1775 1675);
DISPLAY INVISIBLE (-1775 1675);
FORCEPROP 2 LAST CDS_LIB pure_quanta
J 0
(-1775 1675);
DISPLAY INVISIBLE (-1775 1675);
FORCEPROP 1 LAST PATH I39
J 0
(-1700 1730);
DISPLAY 0.723404 (-1700 1730);
PAINT GREEN (-1700 1730);
DISPLAY INVISIBLE (-1700 1730);
FORCEPROP 1 LAST LOCATION PL4
J 0
(-1875 1725);
DISPLAY 0.702128 (-1875 1725);
PAINT AQUA (-1875 1725);
FORCEPROP 0 LASTPIN (-1875 1650) $PN 1
J 2
(-1885 1660);
DISPLAY 0.808511 (-1885 1660);
PAINT WHITE (-1885 1660);
FORCEPROP 0 LASTPIN (-1675 1650) $PN 2
J 0
(-1665 1660);
DISPLAY 0.808511 (-1665 1660);
PAINT WHITE (-1665 1660);
FORCEPROP 0 LAST $SEC 1
J 0
(-1875 1775);
DISPLAY 0.680851 (-1875 1775);
PAINT MONO (-1875 1775);
DISPLAY INVISIBLE (-1875 1775);
FORCEPROP 0 LAST CDS_SEC 1
J 0
(-1875 1775);
DISPLAY 1.021277 (-1875 1775);
DISPLAY INVISIBLE (-1875 1775);
FORCEADD Q_RES..2
(-2325 900);
FORCEPROP 1 LAST PACK_TYPE 0402LF
J 0
(-2285 725);
DISPLAY 0.510638 (-2285 725);
PAINT SKYBLUE (-2285 725);
FORCEPROP 1 LAST PART_NUMBER CS46812FB06
J 0
(-2285 775);
DISPLAY 0.510638 (-2285 775);
PAINT WHITE (-2285 775);
FORCEPROP 1 LAST MATERIAL CHIP
J 0
(-2285 825);
DISPLAY 0.510638 (-2285 825);
PAINT SKYBLUE (-2285 825);
FORCEPROP 1 LAST WATTAGE 1/16W
J 0
(-2285 875);
DISPLAY 0.510638 (-2285 875);
PAINT SKYBLUE (-2285 875);
FORCEPROP 1 LAST TOLERANCE 1%
J 0
(-2280 925);
DISPLAY 0.510638 (-2280 925);
PAINT SKYBLUE (-2280 925);
FORCEPROP 1 LAST VALUE 681K
J 0
(-2280 975);
DISPLAY 0.510638 (-2280 975);
PAINT SKYBLUE (-2280 975);
FORCEPROP 1 LAST PATH I4
J 0
(-2275 1075);
DISPLAY 0.978723 (-2275 1075);
PAINT WHITE (-2275 1075);
DISPLAY INVISIBLE (-2275 1075);
FORCEPROP 2 LAST CDS_LIB pure_quanta
J 0
(-2325 900);
DISPLAY INVISIBLE (-2325 900);
FORCEPROP 1 LAST LOCATION PR521
J 0
(-2280 1025);
DISPLAY 0.702128 (-2280 1025);
PAINT AQUA (-2280 1025);
FORCEPROP 0 LAST $SEC 1
J 0
(-2275 1075);
DISPLAY 0.680851 (-2275 1075);
PAINT MONO (-2275 1075);
DISPLAY INVISIBLE (-2275 1075);
FORCEPROP 0 LAST CDS_SEC 1
J 0
(-2275 1075);
DISPLAY 1.021277 (-2275 1075);
DISPLAY INVISIBLE (-2275 1075);
FORCEPROP 1 LASTPIN (-2325 1000) $PN 1
J 0
(-2320 962);
DISPLAY 0.808511 (-2320 962);
PAINT WHITE (-2320 962);
DISPLAY INVISIBLE (-2320 962);
FORCEPROP 1 LASTPIN (-2325 800) $PN 2
J 0
(-2320 810);
DISPLAY 0.808511 (-2320 810);
PAINT WHITE (-2320 810);
DISPLAY INVISIBLE (-2320 810);
FORCEADD MPQ8633AGLEC807Z..1
(925 500);
FORCEPROP 2 LAST PART_TYPE SMLF
J 0
(650 1475);
DISPLAY 0.510638 (650 1475);
PAINT SKYBLUE (650 1475);
FORCEPROP 1 LAST MATERIAL IC
J 0
(678 1265);
DISPLAY 0.510638 (678 1265);
PAINT SKYBLUE (678 1265);
FORCEPROP 1 LAST PART_NUMBER AL008633007
J 0
(678 1392);
DISPLAY 0.510638 (678 1392);
PAINT WHITE (678 1392);
FORCEPROP 2 LAST VALUE MPQ8633AGLE-C807-Z
J 0
(650 1425);
DISPLAY 0.510638 (650 1425);
PAINT SKYBLUE (650 1425);
FORCEPROP 1 LAST PATH I42
J 0
(925 500);
DISPLAY 0.723404 (925 500);
PAINT GREEN (925 500);
DISPLAY INVISIBLE (925 500);
FORCEPROP 1 LAST CDS_LMAN_SYM_OUTLINE -250,725,250,-725
J 0
(925 500);
DISPLAY 0.468085 (925 500);
PAINT GREEN (925 500);
DISPLAY INVISIBLE (925 500);
FORCEPROP 1 LAST NEEDS_NO_SIZE TRUE
J 0
(925 500);
DISPLAY 0.723404 (925 500);
PAINT GREEN (925 500);
DISPLAY INVISIBLE (925 500);
FORCEPROP 2 LAST CDS_LIB pure_quanta
J 0
(925 500);
DISPLAY INVISIBLE (925 500);
FORCEPROP 1 LAST LOCATION PU38
J 0
(678 1539);
DISPLAY 0.702128 (678 1539);
PAINT AQUA (678 1539);
FORCEPROP 0 LASTPIN (1325 -175) $PN 2
J 0
(1335 -165);
DISPLAY 0.680851 (1335 -165);
PAINT MONO (1335 -165);
FORCEPROP 0 LASTPIN (1325 975) $PN 1
J 0
(1335 985);
DISPLAY 0.680851 (1335 985);
PAINT MONO (1335 985);
FORCEPROP 0 LASTPIN (525 -125) $PN 3
J 2
(515 -115);
DISPLAY 0.680851 (515 -115);
PAINT MONO (515 -115);
FORCEPROP 0 LASTPIN (525 675) $PN 8
J 2
(515 685);
DISPLAY 0.680851 (515 685);
PAINT MONO (515 685);
FORCEPROP 0 LASTPIN (1325 225) $PN 7
J 0
(1335 235);
DISPLAY 0.680851 (1335 235);
PAINT MONO (1335 235);
FORCEPROP 0 LASTPIN (525 475) $PN 4
J 2
(515 485);
DISPLAY 0.680851 (515 485);
PAINT MONO (515 485);
FORCEPROP 0 LASTPIN (1325 -125) $PN 11_18
J 0
(1335 -115);
DISPLAY 0.680851 (1335 -115);
PAINT MONO (1335 -115);
FORCEPROP 0 LASTPIN (1325 1175) $PN 9
J 0
(1335 1185);
DISPLAY 0.680851 (1335 1185);
PAINT MONO (1335 1185);
FORCEPROP 0 LASTPIN (1325 75) $PN 6
J 0
(1335 85);
DISPLAY 0.680851 (1335 85);
PAINT MONO (1335 85);
FORCEPROP 0 LASTPIN (1325 675) $PN 20
J 0
(1335 685);
DISPLAY 0.680851 (1335 685);
PAINT MONO (1335 685);
FORCEPROP 0 LASTPIN (1325 -25) $PN 5
J 0
(1335 -15);
DISPLAY 0.680851 (1335 -15);
PAINT MONO (1335 -15);
FORCEPROP 0 LASTPIN (525 225) $PN 19
J 2
(515 235);
DISPLAY 0.680851 (515 235);
PAINT MONO (515 235);
FORCEPROP 0 LASTPIN (525 1175) $PN 10
J 2
(515 1185);
DISPLAY 0.680851 (515 1185);
PAINT MONO (515 1185);
FORCEPROP 0 LASTPIN (525 1125) $PN 21
J 2
(515 1135);
DISPLAY 0.680851 (515 1135);
PAINT MONO (515 1135);
FORCEPROP 0 LAST $SEC 1
J 0
(700 1575);
DISPLAY 0.680851 (700 1575);
PAINT MONO (700 1575);
DISPLAY INVISIBLE (700 1575);
FORCEPROP 0 LAST CDS_SEC 1
J 0
(700 1575);
DISPLAY 1.021277 (700 1575);
DISPLAY INVISIBLE (700 1575);
FORCEADD Q_RES..2
(2400 1000);
FORCEPROP 1 LAST PACK_TYPE 0402LF
J 0
(2440 825);
DISPLAY 0.510638 (2440 825);
PAINT SKYBLUE (2440 825);
FORCEPROP 1 LAST VALUE 100K
J 0
(2445 1075);
DISPLAY 0.510638 (2445 1075);
PAINT SKYBLUE (2445 1075);
FORCEPROP 1 LAST TOLERANCE 1%
J 0
(2445 1025);
DISPLAY 0.510638 (2445 1025);
PAINT SKYBLUE (2445 1025);
FORCEPROP 1 LAST WATTAGE 1/16W
J 0
(2440 975);
DISPLAY 0.510638 (2440 975);
PAINT SKYBLUE (2440 975);
FORCEPROP 1 LAST MATERIAL EMPTY
J 0
(2440 925);
DISPLAY 0.510638 (2440 925);
PAINT SKYBLUE (2440 925);
FORCEPROP 1 LAST PART_NUMBER CS41002FB09
J 0
(2440 875);
DISPLAY 0.510638 (2440 875);
PAINT WHITE (2440 875);
FORCEPROP 2 LAST CDS_LIB pure_quanta
J 0
(2400 1000);
DISPLAY INVISIBLE (2400 1000);
FORCEPROP 1 LAST PATH I43
J 0
(2450 1175);
DISPLAY 0.978723 (2450 1175);
PAINT WHITE (2450 1175);
DISPLAY INVISIBLE (2450 1175);
FORCEPROP 1 LAST LOCATION PR245
J 0
(2445 1125);
DISPLAY 0.702128 (2445 1125);
PAINT AQUA (2445 1125);
FORCEPROP 0 LAST $SEC 1
J 0
(2450 1175);
DISPLAY 0.680851 (2450 1175);
PAINT MONO (2450 1175);
DISPLAY INVISIBLE (2450 1175);
FORCEPROP 0 LAST CDS_SEC 1
J 0
(2450 1175);
DISPLAY 1.021277 (2450 1175);
DISPLAY INVISIBLE (2450 1175);
FORCEPROP 1 LASTPIN (2400 1100) $PN 1
J 0
(2405 1062);
DISPLAY 0.808511 (2405 1062);
PAINT WHITE (2405 1062);
DISPLAY INVISIBLE (2405 1062);
FORCEPROP 1 LASTPIN (2400 900) $PN 2
J 0
(2405 910);
DISPLAY 0.808511 (2405 910);
PAINT WHITE (2405 910);
DISPLAY INVISIBLE (2405 910);
FORCEADD UNIVERSAL_GND..1
(2400 775);
FORCEPROP 3 LASTPIN (2400 825) SIG_NAME GND\g
J 0
(2410 835);
DISPLAY 0.659574 (2410 835);
PAINT MONO (2410 835);
DISPLAY INVISIBLE (2410 835);
FORCEPROP 1 LAST PATH I44
J 0
(2475 775);
DISPLAY 0.872340 (2475 775);
PAINT AQUA (2475 775);
DISPLAY INVISIBLE (2475 775);
FORCEPROP 1 LAST HDL_POWER GND
J 1
(2425 700);
DISPLAY 0.702128 (2425 700);
PAINT GREEN (2425 700);
DISPLAY INVISIBLE (2425 700);
FORCEPROP 2 LAST CDS_LIB logical_power
J 0
(2400 775);
DISPLAY INVISIBLE (2400 775);
FORCEADD Q_CAP..1
(-350 1400);
FORCEPROP 1 LAST VALUE 0.1UF
J 0
(-300 1450);
DISPLAY 0.510638 (-300 1450);
PAINT SKYBLUE (-300 1450);
FORCEPROP 1 LAST VOLTAGE 25V
J 0
(-300 1400);
DISPLAY 0.510638 (-300 1400);
PAINT SKYBLUE (-300 1400);
FORCEPROP 1 LAST TOLERANCE 10%
J 0
(-300 1350);
DISPLAY 0.510638 (-300 1350);
PAINT SKYBLUE (-300 1350);
FORCEPROP 1 LAST MATERIAL X7R
J 0
(-300 1300);
DISPLAY 0.510638 (-300 1300);
PAINT SKYBLUE (-300 1300);
FORCEPROP 1 LAST PART_NUMBER CH4104K1B00
J 0
(-300 1250);
DISPLAY 0.510638 (-300 1250);
PAINT WHITE (-300 1250);
FORCEPROP 1 LAST PACK_TYPE 0402
J 0
(-300 1200);
DISPLAY 0.510638 (-300 1200);
PAINT SKYBLUE (-300 1200);
FORCEPROP 1 LAST PATH I45
J 0
(-300 1550);
DISPLAY 0.978723 (-300 1550);
PAINT WHITE (-300 1550);
DISPLAY INVISIBLE (-300 1550);
FORCEPROP 2 LAST SEC_TYPE 0402
J 0
(-300 1600);
DISPLAY 1.021277 (-300 1600);
DISPLAY INVISIBLE (-300 1600);
FORCEPROP 2 LAST CDS_LIB pure_quanta
J 0
(-350 1400);
DISPLAY INVISIBLE (-350 1400);
FORCEPROP 1 LAST LOCATION PC210
J 0
(-300 1500);
DISPLAY 0.702128 (-300 1500);
PAINT AQUA (-300 1500);
FORCEPROP 1 LASTPIN (-350 1500) $PN 1
J 0
(-340 1480);
DISPLAY 0.808511 (-340 1480);
PAINT WHITE (-340 1480);
FORCEPROP 1 LASTPIN (-350 1300) $PN 2
J 0
(-340 1280);
DISPLAY 0.808511 (-340 1280);
PAINT WHITE (-340 1280);
FORCEPROP 2 LAST SEC 1
J 0
(-300 1600);
DISPLAY 0.680851 (-300 1600);
PAINT MONO (-300 1600);
DISPLAY INVISIBLE (-300 1600);
FORCEADD OFFPAGE..5
R 2
(5050 1175);
FORCEPROP 2 LAST $XR0 35 
J 0
(5239 1175);
DISPLAY 0.638298 (5239 1175);
PAINT MONO (5239 1175);
FORCEPROP 2 LAST $XR1 52 
J 0
(5329 1175);
DISPLAY 0.638298 (5329 1175);
PAINT MONO (5329 1175);
FORCEPROP 2 LAST $XR2 54 
J 0
(5419 1175);
DISPLAY 0.638298 (5419 1175);
PAINT MONO (5419 1175);
FORCEPROP 2 LAST $XR3 55 
J 0
(5509 1175);
DISPLAY 0.638298 (5509 1175);
PAINT MONO (5509 1175);
FORCEPROP 2 LAST $XR4 56 
J 0
(5599 1175);
DISPLAY 0.638298 (5599 1175);
PAINT MONO (5599 1175);
FORCEPROP 2 LAST CDS_LIB standard
J 0
(5050 1175);
DISPLAY INVISIBLE (5050 1175);
FORCEPROP 1 LAST OFFPAGE TRUE
J 2
(4725 1050);
DISPLAY 0.872340 (4725 1050);
PAINT GREEN (4725 1050);
DISPLAY INVISIBLE (4725 1050);
FORCEPROP 1 LAST COMMENT_BODY TRUE
J 2
(4950 1100);
DISPLAY 0.872340 (4950 1100);
PAINT PEACH (4950 1100);
DISPLAY INVISIBLE (4950 1100);
FORCEPROP 2 LAST PATH I46
J 0
(5225 1250);
DISPLAY 1.021277 (5225 1250);
DISPLAY INVISIBLE (5225 1250);
FORCEADD Q_CAP..1
(-1025 1400);
FORCEPROP 1 LAST VALUE 22UF
J 0
(-975 1450);
DISPLAY 0.510638 (-975 1450);
PAINT SKYBLUE (-975 1450);
FORCEPROP 1 LAST TOLERANCE 20%
J 0
(-975 1350);
DISPLAY 0.510638 (-975 1350);
PAINT SKYBLUE (-975 1350);
FORCEPROP 1 LAST VOLTAGE 16V
J 0
(-975 1400);
DISPLAY 0.510638 (-975 1400);
PAINT SKYBLUE (-975 1400);
FORCEPROP 1 LAST MATERIAL X6S
J 0
(-975 1300);
DISPLAY 0.510638 (-975 1300);
PAINT SKYBLUE (-975 1300);
FORCEPROP 1 LAST PACK_TYPE C0805
J 0
(-975 1200);
DISPLAY 0.510638 (-975 1200);
PAINT SKYBLUE (-975 1200);
FORCEPROP 1 LAST PART_NUMBER CH6223MEA01
J 0
(-975 1250);
DISPLAY 0.510638 (-975 1250);
PAINT WHITE (-975 1250);
FORCEPROP 2 LAST SEC_TYPE C0805
J 0
(-975 1600);
DISPLAY 0.680851 (-975 1600);
DISPLAY INVISIBLE (-975 1600);
FORCEPROP 2 LAST CDS_LIB pure_quanta
J 0
(-1025 1400);
DISPLAY INVISIBLE (-1025 1400);
FORCEPROP 1 LAST PATH I47
J 0
(-975 1550);
DISPLAY 0.978723 (-975 1550);
PAINT WHITE (-975 1550);
DISPLAY INVISIBLE (-975 1550);
FORCEPROP 1 LAST LOCATION PC206
J 0
(-975 1500);
DISPLAY 0.702128 (-975 1500);
PAINT AQUA (-975 1500);
FORCEPROP 1 LASTPIN (-1025 1500) $PN 1
J 0
(-1015 1480);
DISPLAY 0.808511 (-1015 1480);
PAINT WHITE (-1015 1480);
FORCEPROP 1 LASTPIN (-1025 1300) $PN 2
J 0
(-1015 1280);
DISPLAY 0.808511 (-1015 1280);
PAINT WHITE (-1015 1280);
FORCEPROP 2 LAST SEC 1
J 0
(-975 1600);
DISPLAY 0.680851 (-975 1600);
PAINT MONO (-975 1600);
DISPLAY INVISIBLE (-975 1600);
FORCEADD Q_CAP..1
(-650 1400);
FORCEPROP 1 LAST VOLTAGE 16V
J 0
(-600 1400);
DISPLAY 0.510638 (-600 1400);
PAINT SKYBLUE (-600 1400);
FORCEPROP 1 LAST VALUE 22UF
J 0
(-600 1450);
DISPLAY 0.510638 (-600 1450);
PAINT SKYBLUE (-600 1450);
FORCEPROP 1 LAST TOLERANCE 20%
J 0
(-600 1350);
DISPLAY 0.510638 (-600 1350);
PAINT SKYBLUE (-600 1350);
FORCEPROP 1 LAST MATERIAL X6S
J 0
(-600 1300);
DISPLAY 0.510638 (-600 1300);
PAINT SKYBLUE (-600 1300);
FORCEPROP 1 LAST PART_NUMBER CH6223MEA01
J 0
(-600 1250);
DISPLAY 0.510638 (-600 1250);
PAINT WHITE (-600 1250);
FORCEPROP 1 LAST PACK_TYPE C0805
J 0
(-600 1200);
DISPLAY 0.510638 (-600 1200);
PAINT SKYBLUE (-600 1200);
FORCEPROP 2 LAST SEC_TYPE C0805
J 0
(-600 1600);
DISPLAY 0.680851 (-600 1600);
DISPLAY INVISIBLE (-600 1600);
FORCEPROP 2 LAST CDS_LIB pure_quanta
J 0
(-650 1400);
DISPLAY INVISIBLE (-650 1400);
FORCEPROP 1 LAST PATH I48
J 0
(-600 1550);
DISPLAY 0.978723 (-600 1550);
PAINT WHITE (-600 1550);
DISPLAY INVISIBLE (-600 1550);
FORCEPROP 1 LAST LOCATION PC207
J 0
(-600 1500);
DISPLAY 0.702128 (-600 1500);
PAINT AQUA (-600 1500);
FORCEPROP 1 LASTPIN (-650 1500) $PN 1
J 0
(-640 1480);
DISPLAY 0.808511 (-640 1480);
PAINT WHITE (-640 1480);
FORCEPROP 1 LASTPIN (-650 1300) $PN 2
J 0
(-640 1280);
DISPLAY 0.808511 (-640 1280);
PAINT WHITE (-640 1280);
FORCEPROP 2 LAST SEC 1
J 0
(-600 1600);
DISPLAY 0.680851 (-600 1600);
PAINT MONO (-600 1600);
DISPLAY INVISIBLE (-600 1600);
FORCEADD Q_CAP..1
(3550 975);
FORCEPROP 1 LAST VALUE 0.001UF
J 0
(3600 1025);
DISPLAY 0.787234 (3600 1025);
FORCEPROP 1 LAST VOLTAGE 50V
J 0
(3600 975);
DISPLAY 0.787234 (3600 975);
FORCEPROP 1 LAST PACK_TYPE C0402
J 0
(3600 775);
DISPLAY 0.787234 (3600 775);
FORCEPROP 1 LAST PART_NUMBER CH30106KB19
J 0
(3600 825);
DISPLAY 0.787234 (3600 825);
FORCEPROP 1 LAST MATERIAL EMPTY
J 0
(3600 875);
DISPLAY 0.787234 (3600 875);
FORCEPROP 1 LAST TOLERANCE 10%
J 0
(3600 925);
DISPLAY 0.787234 (3600 925);
FORCEPROP 2 LAST CDS_LIB pure_quanta
J 0
(3550 975);
DISPLAY INVISIBLE (3550 975);
FORCEPROP 1 LAST PATH I49
J 0
(3600 1125);
DISPLAY 0.978723 (3600 1125);
PAINT WHITE (3600 1125);
DISPLAY INVISIBLE (3600 1125);
FORCEPROP 1 LAST LOCATION C150
J 0
(3600 1075);
DISPLAY 0.787234 (3600 1075);
FORCEPROP 1 LASTPIN (3550 1075) $PN 1
J 0
(3560 1055);
DISPLAY 0.787234 (3560 1055);
PAINT MONO (3560 1055);
FORCEPROP 1 LASTPIN (3550 875) $PN 2
J 0
(3560 855);
DISPLAY 0.787234 (3560 855);
PAINT MONO (3560 855);
FORCEPROP 0 LAST $SEC 1
J 0
(3600 1125);
DISPLAY 0.680851 (3600 1125);
PAINT MONO (3600 1125);
DISPLAY INVISIBLE (3600 1125);
FORCEPROP 0 LAST CDS_SEC 1
J 0
(3600 1125);
DISPLAY 0.680851 (3600 1125);
DISPLAY INVISIBLE (3600 1125);
FORCEADD VCCAUX15..1
(-2325 1075);
FORCEPROP 3 LASTPIN (-2325 1025) SIG_NAME P12V_AUX\g
J 0
(-2315 1035);
DISPLAY 0.659574 (-2315 1035);
PAINT MONO (-2315 1035);
DISPLAY INVISIBLE (-2315 1035);
FORCEPROP 1 LAST HDL_POWER P12V_AUX
J 1
(-2325 1125);
DISPLAY 0.702128 (-2325 1125);
PAINT GREEN (-2325 1125);
FORCEPROP 2 LAST CDS_LIB logical_power
J 0
(-2325 1075);
DISPLAY INVISIBLE (-2325 1075);
FORCEPROP 1 LAST PATH I5
J 0
(-2275 1100);
DISPLAY 0.872340 (-2275 1100);
PAINT AQUA (-2275 1100);
DISPLAY INVISIBLE (-2275 1100);
FORCEADD UNIVERSAL_GND..1
(3550 775);
FORCEPROP 3 LASTPIN (3550 825) SIG_NAME GND\g
J 0
(3560 835);
DISPLAY 0.659574 (3560 835);
PAINT MONO (3560 835);
DISPLAY INVISIBLE (3560 835);
FORCEPROP 1 LAST PATH I50
J 0
(3625 775);
DISPLAY 0.872340 (3625 775);
PAINT AQUA (3625 775);
DISPLAY INVISIBLE (3625 775);
FORCEPROP 1 LAST HDL_POWER GND
J 1
(3575 700);
DISPLAY 0.702128 (3575 700);
PAINT GREEN (3575 700);
DISPLAY INVISIBLE (3575 700);
FORCEPROP 2 LAST CDS_LIB logical_power
J 0
(3550 775);
DISPLAY INVISIBLE (3550 775);
FORCEADD Q_RES..1
(4275 1175);
FORCEPROP 1 LAST TOLERANCE 5%
J 0
(4275 1075);
DISPLAY 0.978723 (4275 1075);
FORCEPROP 1 LAST MATERIAL CHIP
J 0
(4275 1025);
DISPLAY 0.978723 (4275 1025);
FORCEPROP 1 LAST PACK_TYPE 0402LF
J 0
(4525 1025);
DISPLAY 0.978723 (4525 1025);
FORCEPROP 1 LAST PART_NUMBER CS00002JB13
J 0
(4225 1275);
DISPLAY 0.978723 (4225 1275);
FORCEPROP 1 LAST VALUE 0
J 2
(4250 1075);
DISPLAY 0.978723 (4250 1075);
FORCEPROP 1 LAST WATTAGE 1/16W
J 2
(4250 1025);
DISPLAY 0.978723 (4250 1025);
FORCEPROP 1 LAST PATH I51
J 0
(4225 1325);
DISPLAY 0.978723 (4225 1325);
PAINT WHITE (4225 1325);
DISPLAY INVISIBLE (4225 1325);
FORCEPROP 2 LAST CDS_LIB pure_quanta
J 0
(4275 1175);
DISPLAY INVISIBLE (4275 1175);
FORCEPROP 1 LAST LOCATION R292
J 0
(4225 1225);
DISPLAY 0.978723 (4225 1225);
FORCEPROP 1 LASTPIN (4175 1175) $PN 1
J 0
(4187 1187);
DISPLAY 0.787234 (4187 1187);
PAINT MONO (4187 1187);
FORCEPROP 1 LASTPIN (4375 1175) $PN 2
J 0
(4337 1187);
DISPLAY 0.787234 (4337 1187);
PAINT MONO (4337 1187);
FORCEPROP 0 LAST $SEC 1
J 0
(4225 1325);
DISPLAY 0.680851 (4225 1325);
PAINT MONO (4225 1325);
DISPLAY INVISIBLE (4225 1325);
FORCEPROP 0 LAST CDS_SEC 1
J 0
(4225 1325);
DISPLAY 0.680851 (4225 1325);
DISPLAY INVISIBLE (4225 1325);
FORCEADD Q_CAP..1
(-2275 1475);
FORCEPROP 1 LAST TOLERANCE 10%
J 0
(-2225 1425);
DISPLAY 0.510638 (-2225 1425);
PAINT SKYBLUE (-2225 1425);
FORCEPROP 1 LAST VOLTAGE 25V
J 0
(-2225 1475);
DISPLAY 0.510638 (-2225 1475);
PAINT SKYBLUE (-2225 1475);
FORCEPROP 1 LAST PACK_TYPE 0402
J 0
(-2225 1275);
DISPLAY 0.510638 (-2225 1275);
PAINT SKYBLUE (-2225 1275);
FORCEPROP 1 LAST VALUE 0.1UF
J 0
(-2225 1525);
DISPLAY 0.510638 (-2225 1525);
PAINT SKYBLUE (-2225 1525);
FORCEPROP 1 LAST MATERIAL X7R
J 0
(-2225 1375);
DISPLAY 0.510638 (-2225 1375);
PAINT SKYBLUE (-2225 1375);
FORCEPROP 1 LAST PART_NUMBER CH4104K1B00
J 0
(-2225 1325);
DISPLAY 0.510638 (-2225 1325);
PAINT WHITE (-2225 1325);
FORCEPROP 1 LAST PATH I52
J 0
(-2225 1625);
DISPLAY 0.978723 (-2225 1625);
PAINT WHITE (-2225 1625);
DISPLAY INVISIBLE (-2225 1625);
FORCEPROP 2 LAST CDS_LIB pure_quanta
J 0
(-2275 1475);
DISPLAY INVISIBLE (-2275 1475);
FORCEPROP 1 LAST $LOCATION C241
J 0
(-2225 1575);
DISPLAY 0.702128 (-2225 1575);
PAINT AQUA (-2225 1575);
FORCEPROP 1 LASTPIN (-2275 1575) $PN 1
J 0
(-2265 1555);
DISPLAY 0.787234 (-2265 1555);
PAINT MONO (-2265 1555);
FORCEPROP 1 LASTPIN (-2275 1375) $PN 2
J 0
(-2265 1355);
DISPLAY 0.787234 (-2265 1355);
PAINT MONO (-2265 1355);
FORCEPROP 0 LAST CDS_LOCATION C241
J 0
(-2225 1625);
DISPLAY 0.680851 (-2225 1625);
DISPLAY INVISIBLE (-2225 1625);
FORCEPROP 0 LAST $SEC 1
J 0
(-2225 1625);
DISPLAY 0.680851 (-2225 1625);
PAINT MONO (-2225 1625);
DISPLAY INVISIBLE (-2225 1625);
FORCEPROP 0 LAST CDS_SEC 1
J 0
(-2225 1625);
DISPLAY 0.680851 (-2225 1625);
DISPLAY INVISIBLE (-2225 1625);
FORCEADD UNIVERSAL_GND..1
(-2275 1275);
FORCEPROP 3 LASTPIN (-2275 1325) SIG_NAME GND\g
J 0
(-2265 1335);
DISPLAY 0.659574 (-2265 1335);
PAINT MONO (-2265 1335);
DISPLAY INVISIBLE (-2265 1335);
FORCEPROP 2 LAST CDS_LIB logical_power
J 0
(-2275 1275);
DISPLAY INVISIBLE (-2275 1275);
FORCEPROP 1 LAST PATH I53
J 0
(-2200 1275);
DISPLAY 0.872340 (-2200 1275);
PAINT AQUA (-2200 1275);
DISPLAY INVISIBLE (-2200 1275);
FORCEPROP 1 LAST HDL_POWER GND
J 1
(-2250 1200);
DISPLAY 0.702128 (-2250 1200);
PAINT GREEN (-2250 1200);
DISPLAY INVISIBLE (-2250 1200);
FORCEADD Q_RES..1
(4275 1675);
FORCEPROP 1 LAST VALUE 0
J 2
(4250 1575);
DISPLAY 0.978723 (4250 1575);
FORCEPROP 1 LAST PART_NUMBER CS00002JB13
J 0
(4225 1775);
DISPLAY 0.978723 (4225 1775);
FORCEPROP 1 LAST TOLERANCE 5%
J 0
(4275 1575);
DISPLAY 0.978723 (4275 1575);
FORCEPROP 1 LAST WATTAGE 1/16W
J 2
(4250 1525);
DISPLAY 0.978723 (4250 1525);
FORCEPROP 1 LAST PACK_TYPE 0402LF
J 0
(4525 1525);
DISPLAY 0.978723 (4525 1525);
FORCEPROP 1 LAST MATERIAL EMPTY
J 0
(4275 1525);
DISPLAY 0.978723 (4275 1525);
PAINT RED (4275 1525);
FORCEPROP 1 LAST PATH I54
J 0
(4225 1825);
DISPLAY 0.978723 (4225 1825);
PAINT WHITE (4225 1825);
DISPLAY INVISIBLE (4225 1825);
FORCEPROP 2 LAST CDS_LIB pure_quanta
J 0
(4275 1675);
DISPLAY INVISIBLE (4275 1675);
FORCEPROP 1 LAST $LOCATION R868
J 0
(4225 1725);
DISPLAY 0.978723 (4225 1725);
FORCEPROP 1 LASTPIN (4175 1675) $PN 1
J 0
(4187 1687);
DISPLAY 0.787234 (4187 1687);
PAINT MONO (4187 1687);
FORCEPROP 1 LASTPIN (4375 1675) $PN 2
J 0
(4337 1687);
DISPLAY 0.787234 (4337 1687);
PAINT MONO (4337 1687);
FORCEPROP 0 LAST CDS_LOCATION R868
J 0
(4225 1825);
DISPLAY 0.680851 (4225 1825);
DISPLAY INVISIBLE (4225 1825);
FORCEPROP 0 LAST $SEC 1
J 0
(4225 1825);
DISPLAY 0.680851 (4225 1825);
PAINT MONO (4225 1825);
DISPLAY INVISIBLE (4225 1825);
FORCEPROP 0 LAST CDS_SEC 1
J 0
(4225 1825);
DISPLAY 0.680851 (4225 1825);
DISPLAY INVISIBLE (4225 1825);
FORCEADD OFFPAGE..5
R 2
(5050 1675);
FORCEPROP 2 LAST $XR0 52 
J 0
(5239 1675);
DISPLAY 0.638298 (5239 1675);
PAINT MONO (5239 1675);
FORCEPROP 2 LAST PATH I55
J 0
(5600 1725);
DISPLAY 0.680851 (5600 1725);
DISPLAY INVISIBLE (5600 1725);
FORCEPROP 1 LAST COMMENT_BODY TRUE
J 2
(4950 1600);
DISPLAY 0.872340 (4950 1600);
PAINT PEACH (4950 1600);
DISPLAY INVISIBLE (4950 1600);
FORCEPROP 1 LAST OFFPAGE TRUE
J 2
(4725 1550);
DISPLAY 0.872340 (4725 1550);
PAINT GREEN (4725 1550);
DISPLAY INVISIBLE (4725 1550);
FORCEPROP 2 LAST CDS_LIB standard
J 0
(5050 1675);
DISPLAY INVISIBLE (5050 1675);
FORCEADD AP2205W57..1
(-425 3500);
FORCEPROP 1 LAST MATERIAL IC
J 0
(-625 3725);
DISPLAY 0.723404 (-625 3725);
PAINT GREEN (-625 3725);
FORCEPROP 1 LAST PART_NUMBER AL002205001
J 0
(-625 3800);
DISPLAY 0.723404 (-625 3800);
PAINT GREEN (-625 3800);
FORCEPROP 2 LAST PART_TYPE SMLF
J 0
(-625 3975);
DISPLAY 0.680851 (-625 3975);
FORCEPROP 2 LAST VALUE AP2205-W5-7
J 0
(-625 3925);
DISPLAY 0.680851 (-625 3925);
FORCEPROP 2 LAST CDS_LIB pure_quanta
J 0
(-425 3500);
DISPLAY INVISIBLE (-425 3500);
FORCEPROP 1 LAST PATH I56
J 0
(-425 3500);
DISPLAY 0.723404 (-425 3500);
PAINT GREEN (-425 3500);
DISPLAY INVISIBLE (-425 3500);
FORCEPROP 1 LAST NEEDS_NO_SIZE TRUE
J 0
(-425 3500);
DISPLAY 0.723404 (-425 3500);
PAINT GREEN (-425 3500);
DISPLAY INVISIBLE (-425 3500);
FORCEPROP 1 LAST CDS_LMAN_SYM_OUTLINE -200,200,150,-200
J 0
(-425 3500);
DISPLAY 0.468085 (-425 3500);
PAINT GREEN (-425 3500);
DISPLAY INVISIBLE (-425 3500);
FORCEPROP 1 LAST $LOCATION U56
J 0
(-625 3875);
DISPLAY 0.723404 (-625 3875);
PAINT GREEN (-625 3875);
FORCEPROP 0 LASTPIN (-125 3450) $PN 4
J 0
(-115 3460);
DISPLAY 0.680851 (-115 3460);
PAINT MONO (-115 3460);
FORCEPROP 0 LASTPIN (-775 3500) $PN 3
J 2
(-785 3510);
DISPLAY 0.680851 (-785 3510);
PAINT MONO (-785 3510);
FORCEPROP 0 LASTPIN (-775 3350) $PN 2
J 2
(-785 3360);
DISPLAY 0.680851 (-785 3360);
PAINT MONO (-785 3360);
FORCEPROP 0 LASTPIN (-775 3650) $PN 1
J 2
(-785 3660);
DISPLAY 0.680851 (-785 3660);
PAINT MONO (-785 3660);
FORCEPROP 0 LASTPIN (-125 3650) $PN 5
J 0
(-115 3660);
DISPLAY 0.680851 (-115 3660);
PAINT MONO (-115 3660);
FORCEPROP 0 LAST CDS_LOCATION U56
J 0
(-625 4025);
DISPLAY 0.680851 (-625 4025);
DISPLAY INVISIBLE (-625 4025);
FORCEPROP 0 LAST $SEC 1
J 0
(-625 4025);
DISPLAY 0.680851 (-625 4025);
PAINT MONO (-625 4025);
DISPLAY INVISIBLE (-625 4025);
FORCEPROP 0 LAST CDS_SEC 1
J 0
(-625 4025);
DISPLAY 0.680851 (-625 4025);
DISPLAY INVISIBLE (-625 4025);
FORCEADD Q_RES..2
(325 3200);
FORCEPROP 1 LAST TOLERANCE 1%
J 0
(370 3225);
DISPLAY 0.787234 (370 3225);
FORCEPROP 1 LAST WATTAGE 1/16W
J 0
(365 3175);
DISPLAY 0.787234 (365 3175);
FORCEPROP 1 LAST PART_NUMBER CS31002FB08
J 0
(365 3075);
DISPLAY 0.787234 (365 3075);
FORCEPROP 1 LAST MATERIAL CHIP
J 0
(365 3125);
DISPLAY 0.787234 (365 3125);
FORCEPROP 1 LAST PACK_TYPE 0402LF
J 0
(365 3025);
DISPLAY 0.787234 (365 3025);
FORCEPROP 1 LAST VALUE 10K
J 0
(370 3275);
DISPLAY 0.787234 (370 3275);
FORCEPROP 1 LAST PATH I57
J 0
(375 3375);
DISPLAY 0.978723 (375 3375);
PAINT WHITE (375 3375);
DISPLAY INVISIBLE (375 3375);
FORCEPROP 2 LAST CDS_LIB pure_quanta
J 0
(325 3200);
DISPLAY INVISIBLE (325 3200);
FORCEPROP 1 LAST $LOCATION R677
J 0
(370 3325);
DISPLAY 0.787234 (370 3325);
FORCEPROP 1 LASTPIN (325 3300) $PN 1
J 0
(330 3262);
DISPLAY 0.787234 (330 3262);
PAINT MONO (330 3262);
FORCEPROP 1 LASTPIN (325 3100) $PN 2
J 0
(330 3110);
DISPLAY 0.787234 (330 3110);
PAINT MONO (330 3110);
FORCEPROP 0 LAST CDS_LOCATION R677
J 0
(375 3375);
DISPLAY 0.680851 (375 3375);
DISPLAY INVISIBLE (375 3375);
FORCEPROP 0 LAST $SEC 1
J 0
(375 3375);
DISPLAY 0.680851 (375 3375);
PAINT MONO (375 3375);
DISPLAY INVISIBLE (375 3375);
FORCEPROP 0 LAST CDS_SEC 1
J 0
(375 3375);
DISPLAY 0.680851 (375 3375);
DISPLAY INVISIBLE (375 3375);
FORCEADD UNIVERSAL_GND..1
(-875 3300);
FORCEPROP 3 LASTPIN (-875 3350) SIG_NAME GND\g
J 0
(-865 3360);
DISPLAY 0.659574 (-865 3360);
PAINT MONO (-865 3360);
DISPLAY INVISIBLE (-865 3360);
FORCEPROP 1 LAST HDL_POWER GND
J 1
(-850 3225);
DISPLAY 0.702128 (-850 3225);
PAINT GREEN (-850 3225);
DISPLAY INVISIBLE (-850 3225);
FORCEPROP 1 LAST PATH I58
J 0
(-800 3300);
DISPLAY 0.872340 (-800 3300);
PAINT AQUA (-800 3300);
DISPLAY INVISIBLE (-800 3300);
FORCEPROP 2 LAST CDS_LIB logical_power
J 0
(-875 3300);
DISPLAY INVISIBLE (-875 3300);
FORCEADD UNIVERSAL_POWER..1
(-1125 3975);
FORCEPROP 3 LASTPIN (-1125 3925) SIG_NAME P12V_AUX\g
J 0
(-1115 3935);
DISPLAY 0.659574 (-1115 3935);
PAINT MONO (-1115 3935);
DISPLAY INVISIBLE (-1115 3935);
FORCEPROP 1 LAST HDL_POWER P12V_AUX
J 1
(-1125 4025);
DISPLAY 0.702128 (-1125 4025);
PAINT GREEN (-1125 4025);
FORCEPROP 1 LAST PATH I59
J 0
(-1075 4000);
DISPLAY 0.872340 (-1075 4000);
PAINT AQUA (-1075 4000);
DISPLAY INVISIBLE (-1075 4000);
FORCEPROP 2 LAST CDS_LIB logical_power
J 0
(-1125 3975);
DISPLAY INVISIBLE (-1125 3975);
FORCEADD VCCAUX15..1
(-2275 2000);
FORCEPROP 3 LASTPIN (-2275 1950) SIG_NAME P12V_AUX\g
J 0
(-2265 1960);
DISPLAY 0.659574 (-2265 1960);
PAINT MONO (-2265 1960);
DISPLAY INVISIBLE (-2265 1960);
FORCEPROP 1 LAST HDL_POWER P12V_AUX
J 1
(-2275 2050);
DISPLAY 0.702128 (-2275 2050);
PAINT GREEN (-2275 2050);
FORCEPROP 1 LAST PATH I6
J 0
(-2225 2025);
DISPLAY 0.872340 (-2225 2025);
PAINT AQUA (-2225 2025);
DISPLAY INVISIBLE (-2225 2025);
FORCEPROP 2 LAST CDS_LIB logical_power
J 0
(-2275 2000);
DISPLAY INVISIBLE (-2275 2000);
FORCEADD Q_CAP..1
(-1125 3525);
FORCEPROP 1 LAST PART_NUMBER CH5104KEB02
J 0
(-1325 3475);
DISPLAY 0.808511 (-1325 3475);
FORCEPROP 1 LAST MATERIAL X6S
J 0
(-1325 3525);
DISPLAY 0.808511 (-1325 3525);
FORCEPROP 1 LAST TOLERANCE 10%
J 0
(-1325 3575);
DISPLAY 0.808511 (-1325 3575);
FORCEPROP 1 LAST VOLTAGE 25V
J 0
(-1325 3625);
DISPLAY 0.808511 (-1325 3625);
FORCEPROP 1 LAST VALUE 1UF
J 0
(-1325 3675);
DISPLAY 0.808511 (-1325 3675);
FORCEPROP 1 LAST PACK_TYPE C0402
J 0
(-1325 3425);
DISPLAY 0.808511 (-1325 3425);
FORCEPROP 2 LAST CDS_LIB pure_quanta
J 0
(-1125 3525);
DISPLAY INVISIBLE (-1125 3525);
FORCEPROP 1 LAST PATH I60
J 0
(-1075 3675);
DISPLAY 0.978723 (-1075 3675);
PAINT WHITE (-1075 3675);
DISPLAY INVISIBLE (-1075 3675);
FORCEPROP 1 LAST $LOCATION C226
J 0
(-1325 3725);
DISPLAY 0.808511 (-1325 3725);
FORCEPROP 1 LASTPIN (-1125 3625) $PN 1
J 0
(-1115 3605);
DISPLAY 0.787234 (-1115 3605);
PAINT MONO (-1115 3605);
FORCEPROP 1 LASTPIN (-1125 3425) $PN 2
J 0
(-1115 3405);
DISPLAY 0.787234 (-1115 3405);
PAINT MONO (-1115 3405);
FORCEPROP 0 LAST CDS_LOCATION C226
J 0
(-1325 3775);
DISPLAY 0.680851 (-1325 3775);
DISPLAY INVISIBLE (-1325 3775);
FORCEPROP 0 LAST $SEC 1
J 0
(-1325 3775);
DISPLAY 0.680851 (-1325 3775);
PAINT MONO (-1325 3775);
DISPLAY INVISIBLE (-1325 3775);
FORCEPROP 0 LAST CDS_SEC 1
J 0
(-1325 3775);
DISPLAY 0.680851 (-1325 3775);
DISPLAY INVISIBLE (-1325 3775);
FORCEADD UNIVERSAL_GND..1
(-1125 3300);
FORCEPROP 3 LASTPIN (-1125 3350) SIG_NAME GND\g
J 0
(-1115 3360);
DISPLAY 0.659574 (-1115 3360);
PAINT MONO (-1115 3360);
DISPLAY INVISIBLE (-1115 3360);
FORCEPROP 2 LAST CDS_LIB logical_power
J 0
(-1125 3300);
DISPLAY INVISIBLE (-1125 3300);
FORCEPROP 1 LAST PATH I61
J 0
(-1050 3300);
DISPLAY 0.872340 (-1050 3300);
PAINT AQUA (-1050 3300);
DISPLAY INVISIBLE (-1050 3300);
FORCEPROP 1 LAST HDL_POWER GND
J 1
(-1100 3225);
DISPLAY 0.702128 (-1100 3225);
PAINT GREEN (-1100 3225);
DISPLAY INVISIBLE (-1100 3225);
FORCEADD Q_RES..2
(325 3600);
FORCEPROP 1 LAST PACK_TYPE 0402LF
J 0
(365 3425);
DISPLAY 0.787234 (365 3425);
FORCEPROP 1 LAST PART_NUMBER CS31692FB03
J 0
(365 3475);
DISPLAY 0.787234 (365 3475);
FORCEPROP 1 LAST VALUE 16.9K
J 0
(370 3675);
DISPLAY 0.787234 (370 3675);
FORCEPROP 1 LAST TOLERANCE 1%
J 0
(370 3625);
DISPLAY 0.787234 (370 3625);
FORCEPROP 1 LAST WATTAGE 1/16W
J 0
(365 3575);
DISPLAY 0.787234 (365 3575);
FORCEPROP 1 LAST MATERIAL CHIP
J 0
(365 3525);
DISPLAY 0.787234 (365 3525);
FORCEPROP 2 LAST CDS_LIB pure_quanta
J 0
(325 3600);
DISPLAY INVISIBLE (325 3600);
FORCEPROP 1 LAST PATH I62
J 0
(375 3775);
DISPLAY 0.978723 (375 3775);
PAINT WHITE (375 3775);
DISPLAY INVISIBLE (375 3775);
FORCEPROP 1 LAST $LOCATION R631
J 0
(370 3725);
DISPLAY 0.787234 (370 3725);
FORCEPROP 1 LASTPIN (325 3700) $PN 1
J 0
(330 3662);
DISPLAY 0.787234 (330 3662);
PAINT MONO (330 3662);
FORCEPROP 1 LASTPIN (325 3500) $PN 2
J 0
(330 3510);
DISPLAY 0.787234 (330 3510);
PAINT MONO (330 3510);
FORCEPROP 0 LAST CDS_LOCATION R631
J 0
(375 3775);
DISPLAY 0.680851 (375 3775);
DISPLAY INVISIBLE (375 3775);
FORCEPROP 0 LAST $SEC 1
J 0
(375 3775);
DISPLAY 0.680851 (375 3775);
PAINT MONO (375 3775);
DISPLAY INVISIBLE (375 3775);
FORCEPROP 0 LAST CDS_SEC 1
J 0
(375 3775);
DISPLAY 0.680851 (375 3775);
DISPLAY INVISIBLE (375 3775);
FORCEADD UNIVERSAL_GND..1
(325 3000);
FORCEPROP 3 LASTPIN (325 3050) SIG_NAME GND\g
J 0
(335 3060);
DISPLAY 0.659574 (335 3060);
PAINT MONO (335 3060);
DISPLAY INVISIBLE (335 3060);
FORCEPROP 2 LAST CDS_LIB logical_power
J 0
(325 3000);
DISPLAY INVISIBLE (325 3000);
FORCEPROP 1 LAST PATH I63
J 0
(400 3000);
DISPLAY 0.872340 (400 3000);
PAINT AQUA (400 3000);
DISPLAY INVISIBLE (400 3000);
FORCEPROP 1 LAST HDL_POWER GND
J 1
(350 2925);
DISPLAY 0.702128 (350 2925);
PAINT GREEN (350 2925);
DISPLAY INVISIBLE (350 2925);
FORCEADD UNIVERSAL_GND..1
(850 3325);
FORCEPROP 3 LASTPIN (850 3375) SIG_NAME GND\g
J 0
(860 3385);
DISPLAY 0.659574 (860 3385);
PAINT MONO (860 3385);
DISPLAY INVISIBLE (860 3385);
FORCEPROP 2 LAST CDS_LIB logical_power
J 0
(850 3325);
DISPLAY INVISIBLE (850 3325);
FORCEPROP 1 LAST PATH I65
J 0
(925 3325);
DISPLAY 0.872340 (925 3325);
PAINT AQUA (925 3325);
DISPLAY INVISIBLE (925 3325);
FORCEPROP 1 LAST HDL_POWER GND
J 1
(875 3250);
DISPLAY 0.702128 (875 3250);
PAINT GREEN (875 3250);
DISPLAY INVISIBLE (875 3250);
FORCEADD UNIVERSAL_POWER..1
(850 4000);
FORCEPROP 3 LASTPIN (850 3950) SIG_NAME P3V3_LDO\g
J 0
(860 3960);
DISPLAY 0.659574 (860 3960);
PAINT MONO (860 3960);
DISPLAY INVISIBLE (860 3960);
FORCEPROP 1 LAST HDL_POWER P3V3_LDO
J 1
(850 4050);
DISPLAY 0.702128 (850 4050);
PAINT GREEN (850 4050);
FORCEPROP 2 LAST CDS_LIB logical_power
J 0
(850 4000);
DISPLAY INVISIBLE (850 4000);
FORCEPROP 1 LAST PATH I66
J 0
(900 4025);
DISPLAY 0.872340 (900 4025);
PAINT AQUA (900 4025);
DISPLAY INVISIBLE (900 4025);
FORCEADD Q_CAP..1
(850 3525);
FORCEPROP 1 LAST VALUE 2.2UF
J 0
(900 3575);
DISPLAY 0.978723 (900 3575);
FORCEPROP 1 LAST VOLTAGE 10V
J 0
(900 3525);
DISPLAY 0.978723 (900 3525);
FORCEPROP 1 LAST TOLERANCE 10%
J 0
(900 3475);
DISPLAY 0.978723 (900 3475);
FORCEPROP 1 LAST MATERIAL X6S
J 0
(900 3425);
DISPLAY 0.978723 (900 3425);
FORCEPROP 1 LAST PART_NUMBER CH5222KEB01
J 0
(900 3375);
DISPLAY 0.978723 (900 3375);
FORCEPROP 1 LAST PACK_TYPE C0402
J 0
(900 3325);
DISPLAY 0.978723 (900 3325);
FORCEPROP 2 LAST CDS_LIB pure_quanta
J 0
(850 3525);
DISPLAY INVISIBLE (850 3525);
FORCEPROP 1 LAST PATH I68
J 0
(900 3675);
DISPLAY 0.978723 (900 3675);
PAINT WHITE (900 3675);
DISPLAY INVISIBLE (900 3675);
FORCEPROP 1 LAST LOCATION C227
J 0
(900 3625);
DISPLAY 0.978723 (900 3625);
FORCEPROP 1 LASTPIN (850 3625) $PN 1
J 0
(860 3605);
DISPLAY 0.787234 (860 3605);
PAINT MONO (860 3605);
FORCEPROP 1 LASTPIN (850 3425) $PN 2
J 0
(860 3405);
DISPLAY 0.787234 (860 3405);
PAINT MONO (860 3405);
FORCEPROP 0 LAST $SEC 1
J 0
(900 3675);
DISPLAY 0.680851 (900 3675);
PAINT MONO (900 3675);
DISPLAY INVISIBLE (900 3675);
FORCEPROP 0 LAST CDS_SEC 1
J 0
(900 3675);
DISPLAY 0.680851 (900 3675);
DISPLAY INVISIBLE (900 3675);
FORCEADD UNIVERSAL_GND..1
(-25 -725);
FORCEPROP 3 LASTPIN (-25 -675) SIG_NAME GND\g
J 0
(-15 -665);
DISPLAY 0.659574 (-15 -665);
PAINT MONO (-15 -665);
DISPLAY INVISIBLE (-15 -665);
FORCEPROP 1 LAST PATH I8
J 0
(50 -725);
DISPLAY 0.872340 (50 -725);
PAINT AQUA (50 -725);
DISPLAY INVISIBLE (50 -725);
FORCEPROP 1 LAST HDL_POWER GND
J 1
(0 -800);
DISPLAY 0.702128 (0 -800);
PAINT GREEN (0 -800);
DISPLAY INVISIBLE (0 -800);
FORCEPROP 2 LAST CDS_LIB logical_power
J 0
(-25 -725);
DISPLAY INVISIBLE (-25 -725);
FORCEADD Q_RES..2
(-25 -450);
FORCEPROP 1 LAST MATERIAL CHIP
J 0
(15 -525);
DISPLAY 0.510638 (15 -525);
PAINT SKYBLUE (15 -525);
FORCEPROP 1 LAST WATTAGE 1/16W
J 0
(15 -475);
DISPLAY 0.510638 (15 -475);
PAINT SKYBLUE (15 -475);
FORCEPROP 1 LAST TOLERANCE 1%
J 0
(20 -425);
DISPLAY 0.510638 (20 -425);
PAINT SKYBLUE (20 -425);
FORCEPROP 1 LAST VALUE 20.5K
J 0
(20 -375);
DISPLAY 0.510638 (20 -375);
PAINT SKYBLUE (20 -375);
FORCEPROP 1 LAST PART_NUMBER CS32052FB02
J 0
(15 -575);
DISPLAY 0.510638 (15 -575);
PAINT WHITE (15 -575);
FORCEPROP 1 LAST PACK_TYPE 0402LF
J 0
(15 -625);
DISPLAY 0.510638 (15 -625);
PAINT SKYBLUE (15 -625);
FORCEPROP 1 LAST PATH I9
J 0
(25 -275);
DISPLAY 0.978723 (25 -275);
PAINT WHITE (25 -275);
DISPLAY INVISIBLE (25 -275);
FORCEPROP 2 LAST SEC_TYPE 0402LF
J 0
(25 -225);
DISPLAY 0.680851 (25 -225);
DISPLAY INVISIBLE (25 -225);
FORCEPROP 2 LAST CDS_LIB pure_quanta
J 0
(-25 -450);
DISPLAY INVISIBLE (-25 -450);
FORCEPROP 1 LAST LOCATION PR525
J 0
(20 -325);
DISPLAY 0.702128 (20 -325);
PAINT AQUA (20 -325);
FORCEPROP 1 LASTPIN (-25 -350) $PN 1
J 0
(-20 -388);
DISPLAY 0.808511 (-20 -388);
PAINT WHITE (-20 -388);
FORCEPROP 1 LASTPIN (-25 -550) $PN 2
J 0
(-20 -540);
DISPLAY 0.808511 (-20 -540);
PAINT WHITE (-20 -540);
FORCEPROP 2 LAST SEC 1
J 0
(25 -225);
DISPLAY 0.680851 (25 -225);
PAINT MONO (25 -225);
DISPLAY INVISIBLE (25 -225);
FORCEADD QUANTA_TITLE_BLOCK_C..1
(6550 -1600);
FORCEPROP 0 LAST CDS_CON_LAST_MODIFIED Fri Aug 25 17:25:48 2023
J 0
(4665 -1585);
DISPLAY INVISIBLE (4665 -1585);
FORCEPROP 2 LAST Q_DEPT 
J 1
(2787 -1551);
DISPLAY 1.957447 (2787 -1551);
PAINT GREEN (2787 -1551);
FORCEPROP 1 LAST CUSTOM_TXT_CDS <CON_LAST_MODIFIED>
J 0
(4665 -1585);
DISPLAY 0.978723 (4665 -1585);
FORCEPROP 2 LAST CUSTOM_TXT_CDS <XR_PAGE_TITLE>
J 0
(-1340 3650);
DISPLAY 0.638298 (-1340 3650);
PAINT PINK (-1340 3650);
DISPLAY INVISIBLE (-1340 3650);
FORCEPROP 1 LAST CUSTOM_TXT_CDS <NAME_2>
J 0
(3375 -1550);
FORCEPROP 1 LAST CUSTOM_TXT_CDS <NAME_1>
J 0
(3375 -1425);
FORCEPROP 1 LAST CUSTOM_TXT_CDS <Q_NUMBER>
J 0
(5147 -1497);
DISPLAY 1.212766 (5147 -1497);
FORCEPROP 1 LAST CUSTOM_TXT_CDS <Q_PROJ>
J 0
(4168 -1498);
DISPLAY 1.212766 (4168 -1498);
FORCEPROP 1 LAST CUSTOM_TXT_CDS <Q_REV>
J 0
(6366 -1497);
DISPLAY 1.212766 (6366 -1497);
FORCEPROP 1 LAST CUSTOM_TXT_CDS <CON_PAGE_NUM> OF <CON_TOTAL_PAGES>
J 0
(6104 -1582);
DISPLAY 0.978723 (6104 -1582);
FORCEPROP 1 LAST Q_TITLE MPQ8633A - P5V_AUX
J 0
(-2750 -1575);
DISPLAY 2.446809 (-2750 -1575);
PAINT GREEN (-2750 -1575);
FORCEPROP 2 LAST CDS_XR_PAGE_TITLE CR-51 : @SCM_LIB.SCM(SCH_1):PAGE51
J 0
(-1340 3650);
DISPLAY 0.638298 (-1340 3650);
PAINT PINK (-1340 3650);
DISPLAY INVISIBLE (-1340 3650);
FORCEPROP 2 LAST PAGE_BORDER TRUE
J 0
(-1340 3650);
DISPLAY 0.638298 (-1340 3650);
PAINT PINK (-1340 3650);
DISPLAY INVISIBLE (-1340 3650);
FORCEPROP 1 LAST CDS_LMAN_SYM_OUTLINE -9475,6775,100,-125
J 0
(6550 -1600);
DISPLAY 0.468085 (6550 -1600);
PAINT GREEN (6550 -1600);
DISPLAY INVISIBLE (6550 -1600);
FORCEPROP 2 LAST CDS_LIB pure_quanta
J 0
(6550 -1600);
DISPLAY INVISIBLE (6550 -1600);
FORCEPROP 1 LAST COMMENT_BODY TRUE
J 0
(6562 -1613);
DISPLAY 0.978723 (6562 -1613);
PAINT PEACH (6562 -1613);
DISPLAY INVISIBLE (6562 -1613);
FORCEADD DNS..2
(2425 1000);
PAINT RED (2425 1000);
FORCEPROP 1 LAST COMMENT_BODY TRUE
R 1
J 0
(2500 775);
DISPLAY 0.872340 (2500 775);
PAINT PEACH (2500 775);
DISPLAY INVISIBLE (2500 775);
FORCEPROP 2 LAST CDS_LIB mstr_misc
J 0
(2425 1000);
DISPLAY INVISIBLE (2425 1000);
FORCEADD DNS..2
(3525 1000);
PAINT RED (3525 1000);
FORCEPROP 2 LAST CDS_LIB mstr_misc
J 0
(3525 1000);
DISPLAY INVISIBLE (3525 1000);
FORCEPROP 1 LAST COMMENT_BODY TRUE
R 1
J 0
(3600 775);
DISPLAY 0.872340 (3600 775);
PAINT PEACH (3600 775);
DISPLAY INVISIBLE (3600 775);
FORCEADD CAD_NOTE..1
(3625 1575);
FORCEPROP 0 LAST L1 THE CAP & DAMPING RS FOR PWRGD SHOULD CLOSE TO DRIVE-END
J 0
(3575 1375);
DISPLAY 1.021277 (3575 1375);
PAINT WHITE (3575 1375);
FORCEPROP 1 LAST COMMENT_BODY TRUE
J 0
(3650 1675);
DISPLAY 0.978723 (3650 1675);
PAINT PEACH (3650 1675);
DISPLAY INVISIBLE (3650 1675);
FORCEPROP 2 LAST CDS_LIB logical_power
J 0
(3625 1575);
DISPLAY INVISIBLE (3625 1575);
FORCEADD DESIGN_NOTE..1
(2400 2100);
FORCEPROP 0 LAST L1 P5V_AUX_VCC VOLTAGE LEVEL IS 3V3
J 0
(2450 1925);
DISPLAY 1.021277 (2450 1925);
PAINT WHITE (2450 1925);
FORCEPROP 1 LAST COMMENT_BODY TRUE
J 0
(2425 2200);
DISPLAY 0.978723 (2425 2200);
DISPLAY INVISIBLE (2425 2200);
FORCEPROP 2 LAST CDS_LIB logical_power
J 0
(2400 2100);
DISPLAY INVISIBLE (2400 2100);
FORCEADD DNS..2
(4250 1675);
PAINT RED (4250 1675);
FORCEPROP 2 LAST CDS_LIB mstr_misc
J 0
(4250 1675);
DISPLAY INVISIBLE (4250 1675);
FORCEPROP 1 LAST COMMENT_BODY TRUE
R 1
J 0
(4325 1450);
DISPLAY 0.872340 (4325 1450);
PAINT PEACH (4325 1450);
DISPLAY INVISIBLE (4325 1450);
WIRE 16 -1 (850 3950)(850 3825);
WIRE 16 -1 (-2325 1025)(-2325 1000);
WIRE 16 -1 (-2275 1650)(-2275 1950);
WIRE 16 -1 (-2275 1575)(-2275 1650);
WIRE 16 -1 (-1875 1650)(-2275 1650);
WIRE 16 -1 (2825 1550)(2825 1675);
WIRE 16 -1 (5675 675)(5675 750);
WIRE 16 -1 (5675 -150)(5675 675);
WIRE 16 -1 (5675 675)(5175 675);
WIRE 16 -1 (-1125 3925)(-1125 3650);
WIRE 16 -1 (325 3100)(325 3050);
WIRE 16 -1 (850 3425)(850 3375);
WIRE 16 -1 (-1125 3425)(-1125 3350);
WIRE 16 -1 (-875 3350)(-775 3350);
WIRE 16 -1 (-2275 1375)(-2275 1325);
WIRE 16 -1 (-2075 150)(-2075 250);
WIRE 16 -1 (-1225 475)(-1225 350);
WIRE 16 -1 (-1225 475)(525 475);
WIRE 16 -1 (-650 -75)(-650 -225);
WIRE 16 -1 (-1025 1175)(-1025 1125);
WIRE 16 -1 (-1025 1175)(-650 1175);
WIRE 16 -1 (-1025 1300)(-1025 1175);
WIRE 16 -1 (-25 -675)(-25 -550);
WIRE 16 -1 (1750 -500)(1750 -650);
WIRE 16 -1 (2375 -500)(1750 -500);
WIRE 16 -1 (1750 -375)(1750 -500);
WIRE 16 -1 (2850 -425)(2850 -550);
WIRE 16 -1 (1475 -175)(1475 -375);
WIRE 16 -1 (1475 -125)(1475 -175);
WIRE 16 -1 (1325 -175)(1475 -175);
WIRE 16 -1 (2400 825)(2400 900);
WIRE 16 -1 (3550 875)(3550 825);
WIRE 16 -1 (5025 200)(5025 150);
WIRE 16 -1 (5175 200)(5025 200);
WIRE 16 -1 (5025 200)(4825 200);
WIRE 16 -1 (1325 -125)(1475 -125);
WIRE 16 -1 (-350 1300)(-350 1175);
WIRE 16 -1 (-650 1300)(-650 1175);
WIRE 16 -1 (-650 1175)(-350 1175);
WIRE 16 -1 (-2525 400)(-2525 250);
WIRE 16 -1 (-2525 250)(-2075 250);
WIRE 16 -1 (-2075 250)(-2075 400);
WIRE 16 -1 (1325 75)(2375 75);
WIRE 16 -1 (2375 75)(2375 -500);
WIRE 16 -1 (3725 325)(3725 200);
WIRE 16 -1 (3725 200)(4150 200);
WIRE 16 -1 (4150 325)(4150 200);
WIRE 16 -1 (4500 200)(4150 200);
WIRE 16 -1 (4500 325)(4500 200);
WIRE 16 -1 (4825 200)(4500 200);
WIRE 16 -1 (4825 325)(4825 200);
WIRE 16 -1 (5175 325)(5175 200);
WIRE 16 -1 (3350 675)(3725 675);
WIRE 16 -1 (3725 525)(3725 675);
WIRE 16 -1 (3725 675)(4150 675);
WIRE 16 -1 (4150 525)(4150 675);
WIRE 16 -1 (4500 675)(4150 675);
WIRE 16 -1 (4500 525)(4500 675);
WIRE 16 -1 (4825 675)(4500 675);
WIRE 16 -1 (4825 525)(4825 675);
WIRE 16 -1 (5175 675)(4825 675);
WIRE 16 -1 (5175 675)(5175 525);
WIRE 16 -1 (4700 -150)(5675 -150);
WIRE 16 -1 (4200 -150)(4700 -150);
WIRE 16 -1 (4700 -500)(4700 -150);
WIRE 16 -1 (4200 -500)(4700 -500);
WIRE 16 -1 (-775 3500)(-900 3500);
WIRE 16 -1 (-900 3500)(-900 3650);
WIRE 16 -1 (-900 3650)(-775 3650);
WIRE 16 -1 (-1125 3650)(-1125 3625);
WIRE 16 -1 (-1125 3650)(-900 3650);
WIRE 16 -1 (-125 3650)(-125 3825);
WIRE 16 -1 (-125 3825)(325 3825);
WIRE 16 -1 (325 3825)(325 3700);
WIRE 16 -1 (325 3825)(850 3825);
WIRE 16 -1 (850 3625)(850 3825);
WIRE 16 2175 (-1500 2925)(1350 2925);
WIRE 16 2175 (1350 4250)(1350 2925);
WIRE 16 2175 (-1500 4250)(-1500 2925);
WIRE 16 2175 (-1500 4250)(1350 4250);
WIRE 16 -1 (375 1125)(525 1125);
WIRE 16 -1 (375 1175)(375 1125);
WIRE 16 -1 (525 1175)(375 1175);
WIRE 16 -1 (375 1175)(375 1650);
WIRE 16 -1 (-350 1500)(-350 1650);
WIRE 16 -1 (-350 1650)(375 1650);
WIRE 16 -1 (-650 1500)(-650 1650);
WIRE 16 -1 (-650 1650)(-350 1650);
WIRE 16 -1 (-1025 1500)(-1025 1650);
WIRE 16 -1 (-1025 1650)(-650 1650);
WIRE 16 -1 (-1675 1650)(-1025 1650);
FORCEPROP 2 LAST SIG_NAME SW_P5V_AUX_FLT
J 0
(-1585 1660);
DISPLAY 0.808511 (-1585 1660);
WIRE 16 -1 (-2525 600)(-2525 675);
WIRE 16 -1 (-2525 675)(-2325 675);
WIRE 16 -1 (-2325 800)(-2325 675);
WIRE 16 -1 (-2075 675)(-2325 675);
WIRE 16 -1 (-2075 675)(-2075 600);
WIRE 16 -1 (525 675)(-2075 675);
FORCEPROP 2 LAST SIG_NAME EN_P5V_AUX
J 0
(-1410 685);
DISPLAY 0.808511 (-1410 685);
WIRE 16 -1 (325 3450)(325 3300);
WIRE 16 -1 (325 3450)(325 3500);
WIRE 16 -1 (-125 3450)(325 3450);
FORCEPROP 2 LAST SIG_NAME U56_ADJ_1
J 0
(-60 3460);
DISPLAY 0.851064 (-60 3460);
WIRE 16 -1 (3650 -500)(4000 -500);
WIRE 16 -1 (3650 -150)(3650 -500);
WIRE 16 -1 (3650 -150)(4000 -150);
WIRE 16 -1 (2850 -225)(2850 -150);
WIRE 16 -1 (2850 -150)(3650 -150);
FORCEPROP 2 LAST SIG_NAME P5V_AUX_FB
J 0
(3015 -140);
DISPLAY 0.808511 (3015 -140);
WIRE 16 -1 (2600 -150)(2850 -150);
WIRE 16 -1 (2600 225)(2600 -150);
WIRE 16 -1 (1325 225)(2600 225);
WIRE 16 2175 (-1900 -950)(-775 -950);
WIRE 16 2175 (-775 -950)(-775 -1325);
WIRE 16 2175 (-1900 -950)(-1900 -1325);
WIRE 16 2175 (-1900 -1325)(-775 -1325);
WIRE 16 -1 (1975 925)(1975 975);
WIRE 16 -1 (1325 975)(1975 975);
FORCEPROP 2 LAST SIG_NAME SW_P5V_AUX_BST
J 0
(1415 985);
DISPLAY 0.808511 (1415 985);
WIRE 16 -1 (1975 675)(1325 675);
FORCEPROP 2 LAST SIG_NAME SW_P5V_AUX_SW
J 0
(1440 685);
DISPLAY 0.808511 (1440 685);
WIRE 16 -1 (1975 725)(1975 675);
WIRE 16 -1 (1975 675)(3150 675);
WIRE 16 -1 (5000 1675)(4375 1675);
FORCEPROP 2 LAST SIG_NAME EN_P3V3_R1
J 0
(4415 1685);
DISPLAY 0.808511 (4415 1685);
WIRE 16 -1 (5000 1175)(4375 1175);
FORCEPROP 2 LAST SIG_NAME PWRGD_P5V_AUX
J 0
(4415 1185);
DISPLAY 0.808511 (4415 1185);
WIRE 16 -1 (1325 1175)(2400 1175);
WIRE 16 -1 (2400 1100)(2400 1175);
WIRE 16 -1 (2400 1175)(2825 1175);
WIRE 16 -1 (2825 1350)(2825 1175);
WIRE 16 -1 (3550 1175)(2825 1175);
FORCEPROP 2 LAST SIG_NAME PWRGD_P5V_AUX_R
J 0
(3240 1185);
DISPLAY 0.808511 (3240 1185);
WIRE 16 -1 (3550 1175)(3550 1075);
WIRE 16 -1 (3925 1175)(3550 1175);
WIRE 16 -1 (4175 1175)(3925 1175);
WIRE 16 -1 (3925 1675)(3925 1175);
WIRE 16 -1 (4175 1675)(3925 1675);
WIRE 16 -1 (1750 -25)(1325 -25);
FORCEPROP 2 LAST SIG_NAME P5V_AUX_REF
J 0
(1415 -15);
DISPLAY 0.808511 (1415 -15);
WIRE 16 -1 (1750 -175)(1750 -25);
WIRE 16 -1 (-25 -350)(-25 -125);
WIRE 16 -1 (525 -125)(-25 -125);
FORCEPROP 2 LAST SIG_NAME P5V_AUX_CS
J 0
(65 -115);
DISPLAY 0.808511 (65 -115);
WIRE 16 -1 (-650 125)(-650 225);
WIRE 16 -1 (-650 225)(525 225);
FORCEPROP 2 LAST SIG_NAME P5V_AUX_VCC
J 0
(-535 235);
DISPLAY 0.808511 (-535 235);
WIRE 16 2175 (6166 4431)(6166 3540);
WIRE 16 2175 (4488 3540)(6166 3540);
WIRE 16 2175 (4488 4431)(6166 4431);
WIRE 16 2175 (4488 4431)(4488 3540);
DOT 1 (-1025 1175);
DOT 1 (-650 1175);
DOT 1 (5025 200);
DOT 1 (3925 1175);
DOT 1 (1475 -175);
DOT 1 (325 3450);
DOT 1 (850 3825);
DOT 1 (-1125 3650);
DOT 1 (-900 3650);
DOT 1 (5675 675);
DOT 1 (5175 675);
DOT 1 (4825 675);
DOT 1 (4500 675);
DOT 1 (4150 675);
DOT 1 (4825 200);
DOT 1 (4500 200);
DOT 1 (4700 -150);
DOT 1 (4150 200);
DOT 1 (3550 1175);
DOT 1 (3725 675);
DOT 1 (3650 -150);
DOT 1 (2825 1175);
DOT 1 (2400 1175);
DOT 1 (1975 675);
DOT 1 (2850 -150);
DOT 1 (1750 -500);
DOT 1 (-350 1650);
DOT 1 (-650 1650);
DOT 1 (-2075 675);
DOT 1 (-2075 250);
DOT 1 (-2275 1650);
DOT 1 (-2325 675);
DOT 1 (375 1175);
DOT 1 (-1025 1650);
DOT 1 (325 3825);
FORCENOTE
2ND AL053318002
(-1800 -1250) 0;
DISPLAY LEFT (-1800 -1250);
DISPLAY 1.170213 (-1800 -1250);
FORCENOTE
1ST AL008633007
(-1800 -1150) 0;
DISPLAY LEFT (-1800 -1150);
DISPLAY 1.170213 (-1800 -1150);
FORCENOTE
TO POWER LOGIC FOR BMC SEQUENCE
(-2300 4325) 0;
DISPLAY LEFT (-2300 4325);
DISPLAY 1.170213 (-2300 4325);
FORCENOTE
P3V3_LDO
(-1000 4450) 0;
DISPLAY LEFT (-1000 4450);
DISPLAY 3.148936 (-1000 4450);
PAINT WHITE (-1000 4450);
FORCENOTE
WORK FREQUENCY=600KHZ
(4525 3650) 0;
DISPLAY LEFT (4525 3650);
DISPLAY 0.936170 (4525 3650);
FORCENOTE
SLEW RATE=0.25A/US
(4525 3725) 0;
DISPLAY LEFT (4525 3725);
DISPLAY 0.936170 (4525 3725);
FORCENOTE
TDC=1.4A
(4525 4025) 0;
DISPLAY LEFT (4525 4025);
DISPLAY 0.936170 (4525 4025);
FORCENOTE
MAX CURRENT=1.7A
(4525 3950) 0;
DISPLAY LEFT (4525 3950);
DISPLAY 0.936170 (4525 3950);
FORCENOTE
OVER CURRENT=3A
(4525 3875) 0;
DISPLAY LEFT (4525 3875);
DISPLAY 0.936170 (4525 3875);
FORCENOTE
TRANSIENT TOLERANCE=+/-5%
(4525 4100) 0;
DISPLAY LEFT (4525 4100);
DISPLAY 0.936170 (4525 4100);
FORCENOTE
CURRENT STEP=1.7A
(4525 3825) 0;
DISPLAY LEFT (4525 3825);
DISPLAY 0.936170 (4525 3825);
FORCENOTE
DESIGN SPECIFICATION
(4525 4350) 0;
DISPLAY LEFT (4525 4350);
DISPLAY 1.170213 (4525 4350);
FORCENOTE
OUTPUT VOLTAGE=5V
(4525 4250) 0;
DISPLAY LEFT (4525 4250);
DISPLAY 1.042553 (4525 4250);
FORCENOTE
OUTPUT RIPPLE=1%
(4525 4175) 0;
DISPLAY LEFT (4525 4175);
DISPLAY 0.936170 (4525 4175);
FORCENOTE
P5V_AUX
(575 2200) 0;
DISPLAY LEFT (575 2200);
DISPLAY 3.148936 (575 2200);
PAINT WHITE (575 2200);
FORCENOTE
IC TABLE
(-1800 -1050) 0;
DISPLAY LEFT (-1800 -1050);
DISPLAY 1.170213 (-1800 -1050);
QUIT
